(kicad_sch
	(version 20250114)
	(generator "eeschema")
	(generator_version "9.0")
	(paper "A3")
	(title_block
		(title "RDIMM DDR5 Tester")
		(date "2026-05-21")
		(rev "2.2.0")
		(company "Antmicro")
		(comment 1 "www.antmicro.com")
		(comment 2 "Antmicro")
	)
	(text "User LEDs"
		(exclude_from_sim no)
		(at 17.145 191.135 0)
		(effects
			(font
				(size 2 2)
				(thickness 0.4)
				(bold yes)
			)
			(justify left bottom)
		)
	)
	(text "BANKS HD"
		(exclude_from_sim no)
		(at 15.24 19.685 0)
		(effects
			(font
				(size 3 3)
				(thickness 0.6)
				(bold yes)
			)
			(justify left bottom)
		)
	)
	(no_connect
		(at 318.77 120.65)
	)
	(no_connect
		(at 93.98 135.89)
	)
	(no_connect
		(at 93.98 110.49)
	)
	(no_connect
		(at 93.98 107.95)
	)
	(no_connect
		(at 205.74 90.17)
	)
	(no_connect
		(at 205.74 87.63)
	)
	(no_connect
		(at 318.77 118.11)
	)
	(no_connect
		(at 93.98 128.27)
	)
	(no_connect
		(at 205.74 110.49)
	)
	(no_connect
		(at 318.77 115.57)
	)
	(no_connect
		(at 93.98 92.71)
	)
	(no_connect
		(at 318.77 102.87)
	)
	(no_connect
		(at 205.74 92.71)
	)
	(no_connect
		(at 205.74 95.25)
	)
	(no_connect
		(at 318.77 97.79)
	)
	(no_connect
		(at 93.98 95.25)
	)
	(no_connect
		(at 93.98 113.03)
	)
	(no_connect
		(at 318.77 128.27)
	)
	(no_connect
		(at 318.77 100.33)
	)
	(no_connect
		(at 205.74 115.57)
	)
	(no_connect
		(at 318.77 130.81)
	)
	(no_connect
		(at 93.98 90.17)
	)
	(no_connect
		(at 93.98 133.35)
	)
	(bus_entry
		(at 187.96 82.55)
		(size -2.54 -2.54)
		(stroke
			(width 0)
			(type default)
		)
	)
	(bus_entry
		(at 68.58 97.79)
		(size -1.27 -1.27)
		(stroke
			(width 0)
			(type default)
		)
	)
	(bus_entry
		(at 187.96 77.47)
		(size -2.54 -2.54)
		(stroke
			(width 0)
			(type default)
		)
	)
	(bus_entry
		(at 67.31 119.38)
		(size 1.27 1.27)
		(stroke
			(width 0)
			(type default)
		)
	)
	(bus_entry
		(at 67.31 99.06)
		(size 1.27 1.27)
		(stroke
			(width 0)
			(type default)
		)
	)
	(bus_entry
		(at 292.1 132.08)
		(size 1.27 1.27)
		(stroke
			(width 0)
			(type default)
		)
	)
	(bus_entry
		(at 185.42 95.25)
		(size 2.54 2.54)
		(stroke
			(width 0)
			(type default)
		)
	)
	(bus_entry
		(at 292.1 121.92)
		(size 1.27 1.27)
		(stroke
			(width 0)
			(type default)
		)
	)
	(bus_entry
		(at 161.29 118.11)
		(size -2.54 -2.54)
		(stroke
			(width 0)
			(type default)
		)
	)
	(bus_entry
		(at 185.42 97.79)
		(size 2.54 2.54)
		(stroke
			(width 0)
			(type default)
		)
	)
	(bus_entry
		(at 292.1 124.46)
		(size 1.27 1.27)
		(stroke
			(width 0)
			(type default)
		)
	)
	(bus_entry
		(at 67.31 104.14)
		(size 1.27 1.27)
		(stroke
			(width 0)
			(type default)
		)
	)
	(bus_entry
		(at 292.1 134.62)
		(size 1.27 1.27)
		(stroke
			(width 0)
			(type default)
		)
	)
	(bus_entry
		(at 67.31 114.3)
		(size 1.27 1.27)
		(stroke
			(width 0)
			(type default)
		)
	)
	(bus_entry
		(at 67.31 101.6)
		(size 1.27 1.27)
		(stroke
			(width 0)
			(type default)
		)
	)
	(bus_entry
		(at 187.96 80.01)
		(size -2.54 -2.54)
		(stroke
			(width 0)
			(type default)
		)
	)
	(bus_entry
		(at 161.29 113.03)
		(size -2.54 -2.54)
		(stroke
			(width 0)
			(type default)
		)
	)
	(bus_entry
		(at 67.31 121.92)
		(size 1.27 1.27)
		(stroke
			(width 0)
			(type default)
		)
	)
	(bus_entry
		(at 67.31 116.84)
		(size 1.27 1.27)
		(stroke
			(width 0)
			(type default)
		)
	)
	(bus_entry
		(at 187.96 85.09)
		(size -2.54 -2.54)
		(stroke
			(width 0)
			(type default)
		)
	)
	(bus_entry
		(at 67.31 124.46)
		(size 1.27 1.27)
		(stroke
			(width 0)
			(type default)
		)
	)
	(wire
		(pts
			(xy 106.68 245.11) (xy 116.84 245.11)
		)
		(stroke
			(width 0)
			(type default)
		)
	)
	(wire
		(pts
			(xy 158.75 219.71) (xy 158.75 220.98)
		)
		(stroke
			(width 0)
			(type default)
		)
	)
	(wire
		(pts
			(xy 158.75 226.06) (xy 158.75 229.87)
		)
		(stroke
			(width 0)
			(type default)
		)
	)
	(wire
		(pts
			(xy 193.04 133.35) (xy 205.74 133.35)
		)
		(stroke
			(width 0)
			(type default)
		)
	)
	(wire
		(pts
			(xy 68.58 82.55) (xy 93.98 82.55)
		)
		(stroke
			(width 0)
			(type default)
		)
	)
	(bus
		(pts
			(xy 63.5 93.98) (xy 66.04 93.98)
		)
		(stroke
			(width 0)
			(type default)
		)
	)
	(wire
		(pts
			(xy 292.1 113.03) (xy 318.77 113.03)
		)
		(stroke
			(width 0)
			(type default)
		)
	)
	(wire
		(pts
			(xy 227.33 248.92) (xy 227.33 250.19)
		)
		(stroke
			(width 0)
			(type default)
		)
	)
	(bus
		(pts
			(xy 292.1 121.92) (xy 292.1 124.46)
		)
		(stroke
			(width 0)
			(type default)
		)
	)
	(wire
		(pts
			(xy 86.36 219.71) (xy 86.36 220.98)
		)
		(stroke
			(width 0)
			(type default)
		)
	)
	(wire
		(pts
			(xy 68.58 120.65) (xy 93.98 120.65)
		)
		(stroke
			(width 0)
			(type default)
		)
	)
	(bus
		(pts
			(xy 184.15 72.39) (xy 185.42 73.66)
		)
		(stroke
			(width 0)
			(type default)
		)
	)
	(bus
		(pts
			(xy 290.83 118.11) (xy 292.1 119.38)
		)
		(stroke
			(width 0)
			(type default)
		)
	)
	(wire
		(pts
			(xy 175.26 245.11) (xy 185.42 245.11)
		)
		(stroke
			(width 0)
			(type default)
		)
	)
	(bus
		(pts
			(xy 158.75 109.22) (xy 158.75 110.49)
		)
		(stroke
			(width 0)
			(type default)
		)
	)
	(wire
		(pts
			(xy 193.04 120.65) (xy 205.74 120.65)
		)
		(stroke
			(width 0)
			(type default)
		)
	)
	(wire
		(pts
			(xy 317.5 72.39) (xy 318.77 72.39)
		)
		(stroke
			(width 0)
			(type default)
		)
	)
	(wire
		(pts
			(xy 68.58 87.63) (xy 93.98 87.63)
		)
		(stroke
			(width 0)
			(type default)
		)
	)
	(wire
		(pts
			(xy 193.04 248.92) (xy 193.04 250.19)
		)
		(stroke
			(width 0)
			(type default)
		)
	)
	(wire
		(pts
			(xy 204.47 64.77) (xy 204.47 72.39)
		)
		(stroke
			(width 0)
			(type default)
		)
	)
	(wire
		(pts
			(xy 90.17 72.39) (xy 93.98 72.39)
		)
		(stroke
			(width 0)
			(type default)
		)
	)
	(bus
		(pts
			(xy 66.04 99.06) (xy 67.31 100.33)
		)
		(stroke
			(width 0)
			(type default)
		)
	)
	(wire
		(pts
			(xy 68.58 80.01) (xy 93.98 80.01)
		)
		(stroke
			(width 0)
			(type default)
		)
	)
	(wire
		(pts
			(xy 187.96 82.55) (xy 205.74 82.55)
		)
		(stroke
			(width 0)
			(type default)
		)
	)
	(wire
		(pts
			(xy 193.04 105.41) (xy 205.74 105.41)
		)
		(stroke
			(width 0)
			(type default)
		)
	)
	(wire
		(pts
			(xy 204.47 72.39) (xy 205.74 72.39)
		)
		(stroke
			(width 0)
			(type default)
		)
	)
	(wire
		(pts
			(xy 187.96 77.47) (xy 205.74 77.47)
		)
		(stroke
			(width 0)
			(type default)
		)
	)
	(wire
		(pts
			(xy 68.58 100.33) (xy 93.98 100.33)
		)
		(stroke
			(width 0)
			(type default)
		)
	)
	(bus
		(pts
			(xy 154.94 107.95) (xy 157.48 107.95)
		)
		(stroke
			(width 0)
			(type default)
		)
	)
	(wire
		(pts
			(xy 124.46 219.71) (xy 124.46 220.98)
		)
		(stroke
			(width 0)
			(type default)
		)
	)
	(bus
		(pts
			(xy 185.42 74.93) (xy 185.42 77.47)
		)
		(stroke
			(width 0)
			(type default)
		)
	)
	(wire
		(pts
			(xy 68.58 77.47) (xy 93.98 77.47)
		)
		(stroke
			(width 0)
			(type default)
		)
	)
	(bus
		(pts
			(xy 157.48 107.95) (xy 158.75 109.22)
		)
		(stroke
			(width 0)
			(type default)
		)
	)
	(wire
		(pts
			(xy 193.04 130.81) (xy 205.74 130.81)
		)
		(stroke
			(width 0)
			(type default)
		)
	)
	(wire
		(pts
			(xy 86.36 226.06) (xy 86.36 229.87)
		)
		(stroke
			(width 0)
			(type default)
		)
	)
	(wire
		(pts
			(xy 187.96 80.01) (xy 205.74 80.01)
		)
		(stroke
			(width 0)
			(type default)
		)
	)
	(wire
		(pts
			(xy 158.75 248.92) (xy 158.75 250.19)
		)
		(stroke
			(width 0)
			(type default)
		)
	)
	(wire
		(pts
			(xy 68.58 115.57) (xy 93.98 115.57)
		)
		(stroke
			(width 0)
			(type default)
		)
	)
	(wire
		(pts
			(xy 86.36 248.92) (xy 86.36 250.19)
		)
		(stroke
			(width 0)
			(type default)
		)
	)
	(bus
		(pts
			(xy 185.42 95.25) (xy 185.42 97.79)
		)
		(stroke
			(width 0)
			(type default)
		)
	)
	(bus
		(pts
			(xy 66.04 110.49) (xy 67.31 111.76)
		)
		(stroke
			(width 0)
			(type default)
		)
	)
	(wire
		(pts
			(xy 90.17 66.04) (xy 90.17 72.39)
		)
		(stroke
			(width 0)
			(type default)
		)
	)
	(wire
		(pts
			(xy 68.58 245.11) (xy 78.74 245.11)
		)
		(stroke
			(width 0)
			(type default)
		)
	)
	(bus
		(pts
			(xy 181.61 77.47) (xy 184.15 77.47)
		)
		(stroke
			(width 0)
			(type default)
		)
	)
	(wire
		(pts
			(xy 124.46 226.06) (xy 124.46 229.87)
		)
		(stroke
			(width 0)
			(type default)
		)
	)
	(wire
		(pts
			(xy 292.1 95.25) (xy 318.77 95.25)
		)
		(stroke
			(width 0)
			(type default)
		)
	)
	(bus
		(pts
			(xy 185.42 78.74) (xy 185.42 80.01)
		)
		(stroke
			(width 0)
			(type default)
		)
	)
	(bus
		(pts
			(xy 63.5 110.49) (xy 66.04 110.49)
		)
		(stroke
			(width 0)
			(type default)
		)
	)
	(bus
		(pts
			(xy 158.75 110.49) (xy 158.75 115.57)
		)
		(stroke
			(width 0)
			(type default)
		)
	)
	(bus
		(pts
			(xy 290.83 128.27) (xy 292.1 129.54)
		)
		(stroke
			(width 0)
			(type default)
		)
	)
	(wire
		(pts
			(xy 82.55 130.81) (xy 93.98 130.81)
		)
		(stroke
			(width 0)
			(type default)
		)
	)
	(bus
		(pts
			(xy 67.31 116.84) (xy 67.31 119.38)
		)
		(stroke
			(width 0)
			(type default)
		)
	)
	(bus
		(pts
			(xy 67.31 100.33) (xy 67.31 101.6)
		)
		(stroke
			(width 0)
			(type default)
		)
	)
	(wire
		(pts
			(xy 292.1 105.41) (xy 318.77 105.41)
		)
		(stroke
			(width 0)
			(type default)
		)
	)
	(wire
		(pts
			(xy 292.1 107.95) (xy 318.77 107.95)
		)
		(stroke
			(width 0)
			(type default)
		)
	)
	(wire
		(pts
			(xy 68.58 97.79) (xy 93.98 97.79)
		)
		(stroke
			(width 0)
			(type default)
		)
	)
	(wire
		(pts
			(xy 292.1 82.55) (xy 318.77 82.55)
		)
		(stroke
			(width 0)
			(type default)
		)
	)
	(wire
		(pts
			(xy 68.58 123.19) (xy 93.98 123.19)
		)
		(stroke
			(width 0)
			(type default)
		)
	)
	(wire
		(pts
			(xy 161.29 118.11) (xy 205.74 118.11)
		)
		(stroke
			(width 0)
			(type default)
		)
	)
	(wire
		(pts
			(xy 193.04 219.71) (xy 193.04 220.98)
		)
		(stroke
			(width 0)
			(type default)
		)
	)
	(wire
		(pts
			(xy 158.75 234.95) (xy 158.75 236.22)
		)
		(stroke
			(width 0)
			(type default)
		)
	)
	(bus
		(pts
			(xy 67.31 111.76) (xy 67.31 114.3)
		)
		(stroke
			(width 0)
			(type default)
		)
	)
	(wire
		(pts
			(xy 124.46 234.95) (xy 124.46 236.22)
		)
		(stroke
			(width 0)
			(type default)
		)
	)
	(wire
		(pts
			(xy 161.29 113.03) (xy 205.74 113.03)
		)
		(stroke
			(width 0)
			(type default)
		)
	)
	(bus
		(pts
			(xy 63.5 99.06) (xy 66.04 99.06)
		)
		(stroke
			(width 0)
			(type default)
		)
	)
	(bus
		(pts
			(xy 67.31 121.92) (xy 67.31 124.46)
		)
		(stroke
			(width 0)
			(type default)
		)
	)
	(bus
		(pts
			(xy 184.15 92.71) (xy 185.42 93.98)
		)
		(stroke
			(width 0)
			(type default)
		)
	)
	(bus
		(pts
			(xy 67.31 119.38) (xy 67.31 121.92)
		)
		(stroke
			(width 0)
			(type default)
		)
	)
	(wire
		(pts
			(xy 292.1 90.17) (xy 318.77 90.17)
		)
		(stroke
			(width 0)
			(type default)
		)
	)
	(bus
		(pts
			(xy 292.1 132.08) (xy 292.1 134.62)
		)
		(stroke
			(width 0)
			(type default)
		)
	)
	(wire
		(pts
			(xy 317.5 64.77) (xy 317.5 72.39)
		)
		(stroke
			(width 0)
			(type default)
		)
	)
	(wire
		(pts
			(xy 68.58 102.87) (xy 93.98 102.87)
		)
		(stroke
			(width 0)
			(type default)
		)
	)
	(bus
		(pts
			(xy 185.42 93.98) (xy 185.42 95.25)
		)
		(stroke
			(width 0)
			(type default)
		)
	)
	(polyline
		(pts
			(xy 12.7 184.15) (xy 407.67 184.15)
		)
		(stroke
			(width 0)
			(type default)
		)
	)
	(bus
		(pts
			(xy 67.31 96.52) (xy 67.31 99.06)
		)
		(stroke
			(width 0)
			(type default)
		)
	)
	(bus
		(pts
			(xy 67.31 101.6) (xy 67.31 104.14)
		)
		(stroke
			(width 0)
			(type default)
		)
	)
	(bus
		(pts
			(xy 185.42 80.01) (xy 185.42 82.55)
		)
		(stroke
			(width 0)
			(type default)
		)
	)
	(wire
		(pts
			(xy 187.96 85.09) (xy 205.74 85.09)
		)
		(stroke
			(width 0)
			(type default)
		)
	)
	(wire
		(pts
			(xy 292.1 110.49) (xy 318.77 110.49)
		)
		(stroke
			(width 0)
			(type default)
		)
	)
	(wire
		(pts
			(xy 193.04 102.87) (xy 205.74 102.87)
		)
		(stroke
			(width 0)
			(type default)
		)
	)
	(bus
		(pts
			(xy 288.29 118.11) (xy 290.83 118.11)
		)
		(stroke
			(width 0)
			(type default)
		)
	)
	(wire
		(pts
			(xy 140.97 245.11) (xy 151.13 245.11)
		)
		(stroke
			(width 0)
			(type default)
		)
	)
	(bus
		(pts
			(xy 184.15 77.47) (xy 185.42 78.74)
		)
		(stroke
			(width 0)
			(type default)
		)
	)
	(wire
		(pts
			(xy 227.33 233.68) (xy 227.33 236.22)
		)
		(stroke
			(width 0)
			(type default)
		)
	)
	(wire
		(pts
			(xy 193.04 123.19) (xy 205.74 123.19)
		)
		(stroke
			(width 0)
			(type default)
		)
	)
	(wire
		(pts
			(xy 292.1 85.09) (xy 318.77 85.09)
		)
		(stroke
			(width 0)
			(type default)
		)
	)
	(bus
		(pts
			(xy 292.1 129.54) (xy 292.1 132.08)
		)
		(stroke
			(width 0)
			(type default)
		)
	)
	(bus
		(pts
			(xy 185.42 73.66) (xy 185.42 74.93)
		)
		(stroke
			(width 0)
			(type default)
		)
	)
	(wire
		(pts
			(xy 292.1 87.63) (xy 318.77 87.63)
		)
		(stroke
			(width 0)
			(type default)
		)
	)
	(bus
		(pts
			(xy 66.04 93.98) (xy 67.31 95.25)
		)
		(stroke
			(width 0)
			(type default)
		)
	)
	(wire
		(pts
			(xy 193.04 107.95) (xy 205.74 107.95)
		)
		(stroke
			(width 0)
			(type default)
		)
	)
	(wire
		(pts
			(xy 293.37 123.19) (xy 318.77 123.19)
		)
		(stroke
			(width 0)
			(type default)
		)
	)
	(wire
		(pts
			(xy 86.36 234.95) (xy 86.36 236.22)
		)
		(stroke
			(width 0)
			(type default)
		)
	)
	(wire
		(pts
			(xy 293.37 135.89) (xy 318.77 135.89)
		)
		(stroke
			(width 0)
			(type default)
		)
	)
	(wire
		(pts
			(xy 68.58 125.73) (xy 93.98 125.73)
		)
		(stroke
			(width 0)
			(type default)
		)
	)
	(wire
		(pts
			(xy 209.55 245.11) (xy 219.71 245.11)
		)
		(stroke
			(width 0)
			(type default)
		)
	)
	(wire
		(pts
			(xy 187.96 100.33) (xy 205.74 100.33)
		)
		(stroke
			(width 0)
			(type default)
		)
	)
	(bus
		(pts
			(xy 180.34 92.71) (xy 184.15 92.71)
		)
		(stroke
			(width 0)
			(type default)
		)
	)
	(wire
		(pts
			(xy 193.04 226.06) (xy 193.04 229.87)
		)
		(stroke
			(width 0)
			(type default)
		)
	)
	(wire
		(pts
			(xy 193.04 135.89) (xy 205.74 135.89)
		)
		(stroke
			(width 0)
			(type default)
		)
	)
	(wire
		(pts
			(xy 193.04 125.73) (xy 205.74 125.73)
		)
		(stroke
			(width 0)
			(type default)
		)
	)
	(wire
		(pts
			(xy 124.46 248.92) (xy 124.46 250.19)
		)
		(stroke
			(width 0)
			(type default)
		)
	)
	(wire
		(pts
			(xy 68.58 85.09) (xy 93.98 85.09)
		)
		(stroke
			(width 0)
			(type default)
		)
	)
	(wire
		(pts
			(xy 292.1 77.47) (xy 318.77 77.47)
		)
		(stroke
			(width 0)
			(type default)
		)
	)
	(wire
		(pts
			(xy 293.37 125.73) (xy 318.77 125.73)
		)
		(stroke
			(width 0)
			(type default)
		)
	)
	(bus
		(pts
			(xy 288.29 128.27) (xy 290.83 128.27)
		)
		(stroke
			(width 0)
			(type default)
		)
	)
	(wire
		(pts
			(xy 193.04 234.95) (xy 193.04 236.22)
		)
		(stroke
			(width 0)
			(type default)
		)
	)
	(bus
		(pts
			(xy 67.31 95.25) (xy 67.31 96.52)
		)
		(stroke
			(width 0)
			(type default)
		)
	)
	(wire
		(pts
			(xy 227.33 218.44) (xy 227.33 219.71)
		)
		(stroke
			(width 0)
			(type default)
		)
	)
	(wire
		(pts
			(xy 292.1 80.01) (xy 318.77 80.01)
		)
		(stroke
			(width 0)
			(type default)
		)
	)
	(wire
		(pts
			(xy 293.37 133.35) (xy 318.77 133.35)
		)
		(stroke
			(width 0)
			(type default)
		)
	)
	(wire
		(pts
			(xy 68.58 105.41) (xy 93.98 105.41)
		)
		(stroke
			(width 0)
			(type default)
		)
	)
	(bus
		(pts
			(xy 181.61 72.39) (xy 184.15 72.39)
		)
		(stroke
			(width 0)
			(type default)
		)
	)
	(wire
		(pts
			(xy 227.33 224.79) (xy 227.33 228.6)
		)
		(stroke
			(width 0)
			(type default)
		)
	)
	(wire
		(pts
			(xy 292.1 92.71) (xy 318.77 92.71)
		)
		(stroke
			(width 0)
			(type default)
		)
	)
	(wire
		(pts
			(xy 193.04 128.27) (xy 205.74 128.27)
		)
		(stroke
			(width 0)
			(type default)
		)
	)
	(bus
		(pts
			(xy 67.31 114.3) (xy 67.31 116.84)
		)
		(stroke
			(width 0)
			(type default)
		)
	)
	(wire
		(pts
			(xy 68.58 118.11) (xy 93.98 118.11)
		)
		(stroke
			(width 0)
			(type default)
		)
	)
	(bus
		(pts
			(xy 292.1 119.38) (xy 292.1 121.92)
		)
		(stroke
			(width 0)
			(type default)
		)
	)
	(wire
		(pts
			(xy 187.96 97.79) (xy 205.74 97.79)
		)
		(stroke
			(width 0)
			(type default)
		)
	)
	(label "USR_LED5"
		(at 209.55 245.11 0)
		(effects
			(font
				(size 1.27 1.27)
			)
			(justify left bottom)
		)
	)
	(label "FPGA_DDR.SCL"
		(at 293.37 125.73 0)
		(effects
			(font
				(size 1.27 1.27)
			)
			(justify left bottom)
		)
	)
	(label "USR_LED5"
		(at 68.58 77.47 0)
		(effects
			(font
				(size 1.27 1.27)
			)
			(justify left bottom)
		)
	)
	(label "FPGA_DDR.SDA"
		(at 293.37 123.19 0)
		(effects
			(font
				(size 1.27 1.27)
			)
			(justify left bottom)
		)
	)
	(label "HDMI_CTL.SCL"
		(at 161.29 118.11 0)
		(effects
			(font
				(size 1.27 1.27)
			)
			(justify left bottom)
		)
	)
	(label "AUX.RST"
		(at 68.58 115.57 0)
		(effects
			(font
				(size 1.27 1.27)
			)
			(justify left bottom)
		)
	)
	(label "USR_LED4"
		(at 68.58 80.01 0)
		(effects
			(font
				(size 1.27 1.27)
			)
			(justify left bottom)
		)
	)
	(label "HDMI_OUT_I2C.SDA"
		(at 187.96 82.55 0)
		(effects
			(font
				(size 1.27 1.27)
			)
			(justify left bottom)
		)
	)
	(label "USR_LED1"
		(at 68.58 245.11 0)
		(effects
			(font
				(size 1.27 1.27)
			)
			(justify left bottom)
		)
	)
	(label "FPGA_PWR.SDA"
		(at 293.37 133.35 0)
		(effects
			(font
				(size 1.27 1.27)
			)
			(justify left bottom)
		)
	)
	(label "AUX.TDO"
		(at 68.58 125.73 0)
		(effects
			(font
				(size 1.27 1.27)
			)
			(justify left bottom)
		)
	)
	(label "FPGA_I3C.SCL"
		(at 187.96 100.33 0)
		(effects
			(font
				(size 1.27 1.27)
			)
			(justify left bottom)
		)
	)
	(label "USR_LED4"
		(at 175.26 245.11 0)
		(effects
			(font
				(size 1.27 1.27)
			)
			(justify left bottom)
		)
	)
	(label "FPGA_PWR.SCL"
		(at 293.37 135.89 0)
		(effects
			(font
				(size 1.27 1.27)
			)
			(justify left bottom)
		)
	)
	(label "USR_LED2"
		(at 106.68 245.11 0)
		(effects
			(font
				(size 1.27 1.27)
			)
			(justify left bottom)
		)
	)
	(label "UART1.RX"
		(at 68.58 105.41 0)
		(effects
			(font
				(size 1.27 1.27)
			)
			(justify left bottom)
		)
	)
	(label "HDMI_IN_I2C.SCL"
		(at 187.96 80.01 0)
		(effects
			(font
				(size 1.27 1.27)
			)
			(justify left bottom)
		)
	)
	(label "HDMI_CTL.SDA"
		(at 161.29 113.03 0)
		(effects
			(font
				(size 1.27 1.27)
			)
			(justify left bottom)
		)
	)
	(label "HDMI_IN_I2C.SDA"
		(at 187.96 77.47 0)
		(effects
			(font
				(size 1.27 1.27)
			)
			(justify left bottom)
		)
	)
	(label "USR_LED3"
		(at 68.58 82.55 0)
		(effects
			(font
				(size 1.27 1.27)
			)
			(justify left bottom)
		)
	)
	(label "AUX.TCK"
		(at 68.58 120.65 0)
		(effects
			(font
				(size 1.27 1.27)
			)
			(justify left bottom)
		)
	)
	(label "HDMI_OUT_I2C.SCL"
		(at 187.96 85.09 0)
		(effects
			(font
				(size 1.27 1.27)
			)
			(justify left bottom)
		)
	)
	(label "USR_LED1"
		(at 68.58 87.63 0)
		(effects
			(font
				(size 1.27 1.27)
			)
			(justify left bottom)
		)
	)
	(label "USR_LED2"
		(at 68.58 85.09 0)
		(effects
			(font
				(size 1.27 1.27)
			)
			(justify left bottom)
		)
	)
	(label "UART0.RX"
		(at 68.58 97.79 0)
		(effects
			(font
				(size 1.27 1.27)
			)
			(justify left bottom)
		)
	)
	(label "AUX.TMS"
		(at 68.58 118.11 0)
		(effects
			(font
				(size 1.27 1.27)
			)
			(justify left bottom)
		)
	)
	(label "UART0.TX"
		(at 68.58 100.33 0)
		(effects
			(font
				(size 1.27 1.27)
			)
			(justify left bottom)
		)
	)
	(label "FPGA_I3C.SDA"
		(at 187.96 97.79 0)
		(effects
			(font
				(size 1.27 1.27)
			)
			(justify left bottom)
		)
	)
	(label "USR_LED3"
		(at 140.97 245.11 0)
		(effects
			(font
				(size 1.27 1.27)
			)
			(justify left bottom)
		)
	)
	(label "UART1.TX"
		(at 68.58 102.87 0)
		(effects
			(font
				(size 1.27 1.27)
			)
			(justify left bottom)
		)
	)
	(label "AUX.TDI"
		(at 68.58 123.19 0)
		(effects
			(font
				(size 1.27 1.27)
			)
			(justify left bottom)
		)
	)
	(global_label "HDMI_IN_HPD"
		(shape output)
		(at 193.04 125.73 180)
		(fields_autoplaced yes)
		(effects
			(font
				(size 1.27 1.27)
			)
			(justify right)
		)
		(property "Intersheetrefs" "${INTERSHEET_REFS}"
			(at 178.3113 125.73 0)
			(effects
				(font
					(size 1.27 1.27)
				)
				(justify right)
			)
		)
	)
	(global_label "HOT_SWAP_RED"
		(shape input)
		(at 292.1 80.01 180)
		(fields_autoplaced yes)
		(effects
			(font
				(size 1.27 1.27)
			)
			(justify right)
		)
		(property "Intersheetrefs" "${INTERSHEET_REFS}"
			(at 275.5034 79.9306 0)
			(effects
				(font
					(size 1.27 1.27)
				)
				(justify right)
			)
		)
	)
	(global_label "HDMI_OUT_HPD"
		(shape input)
		(at 193.04 120.65 180)
		(fields_autoplaced yes)
		(effects
			(font
				(size 1.27 1.27)
			)
			(justify right)
		)
		(property "Intersheetrefs" "${INTERSHEET_REFS}"
			(at 176.618 120.65 0)
			(effects
				(font
					(size 1.27 1.27)
				)
				(justify right)
			)
		)
	)
	(global_label "~{FPGA_I3C_EXT_PU}"
		(shape input)
		(at 193.04 105.41 180)
		(fields_autoplaced yes)
		(effects
			(font
				(size 1.27 1.27)
			)
			(justify right)
		)
		(property "Intersheetrefs" "${INTERSHEET_REFS}"
			(at 174.0781 105.41 0)
			(effects
				(font
					(size 1.27 1.27)
				)
				(justify right)
			)
		)
	)
	(global_label "~{SI_5319_RST}"
		(shape output)
		(at 193.04 128.27 180)
		(fields_autoplaced yes)
		(effects
			(font
				(size 1.27 1.27)
			)
			(justify right)
		)
		(property "Intersheetrefs" "${INTERSHEET_REFS}"
			(at 178.6744 128.27 0)
			(effects
				(font
					(size 1.27 1.27)
				)
				(justify right)
			)
		)
	)
	(global_label "SD_SEL"
		(shape input)
		(at 193.04 133.35 180)
		(fields_autoplaced yes)
		(effects
			(font
				(size 1.27 1.27)
			)
			(justify right)
		)
		(property "Intersheetrefs" "${INTERSHEET_REFS}"
			(at 183.2211 133.35 0)
			(effects
				(font
					(size 1.27 1.27)
				)
				(justify right)
			)
		)
	)
	(global_label "FPGA_POWER_OFF"
		(shape input)
		(at 292.1 107.95 180)
		(fields_autoplaced yes)
		(effects
			(font
				(size 1.27 1.27)
			)
			(justify right)
		)
		(property "Intersheetrefs" "${INTERSHEET_REFS}"
			(at 273.1448 107.8706 0)
			(effects
				(font
					(size 1.27 1.27)
				)
				(justify right)
			)
		)
	)
	(global_label "FPGA_POWER_CYCLE"
		(shape input)
		(at 292.1 110.49 180)
		(fields_autoplaced yes)
		(effects
			(font
				(size 1.27 1.27)
			)
			(justify right)
		)
		(property "Intersheetrefs" "${INTERSHEET_REFS}"
			(at 270.8468 110.4106 0)
			(effects
				(font
					(size 1.27 1.27)
				)
				(justify right)
			)
		)
	)
	(global_label "USER_IN"
		(shape input)
		(at 292.1 90.17 180)
		(fields_autoplaced yes)
		(effects
			(font
				(size 1.27 1.27)
			)
			(justify right)
		)
		(property "Intersheetrefs" "${INTERSHEET_REFS}"
			(at 281.9071 90.17 0)
			(effects
				(font
					(size 1.27 1.27)
				)
				(justify right)
			)
		)
	)
	(global_label "HDMI_OE"
		(shape output)
		(at 193.04 123.19 180)
		(fields_autoplaced yes)
		(effects
			(font
				(size 1.27 1.27)
			)
			(justify right)
		)
		(property "Intersheetrefs" "${INTERSHEET_REFS}"
			(at 182.6052 123.19 0)
			(effects
				(font
					(size 1.27 1.27)
				)
				(justify right)
			)
		)
	)
	(global_label "FAN_PWM"
		(shape input)
		(at 292.1 113.03 180)
		(fields_autoplaced yes)
		(effects
			(font
				(size 1.27 1.27)
			)
			(justify right)
		)
		(property "Intersheetrefs" "${INTERSHEET_REFS}"
			(at 281.1277 112.9506 0)
			(effects
				(font
					(size 1.27 1.27)
				)
				(justify right)
			)
		)
	)
	(global_label "HDMI_IN_CD"
		(shape input)
		(at 193.04 102.87 180)
		(fields_autoplaced yes)
		(effects
			(font
				(size 1.27 1.27)
			)
			(justify right)
		)
		(property "Intersheetrefs" "${INTERSHEET_REFS}"
			(at 179.6418 102.87 0)
			(effects
				(font
					(size 1.27 1.27)
				)
				(justify right)
			)
		)
	)
	(global_label "HOT_SWAP_BUTTON"
		(shape input)
		(at 292.1 85.09 180)
		(fields_autoplaced yes)
		(effects
			(font
				(size 1.27 1.27)
			)
			(justify right)
		)
		(property "Intersheetrefs" "${INTERSHEET_REFS}"
			(at 271.9958 85.1694 0)
			(effects
				(font
					(size 1.27 1.27)
				)
				(justify right)
			)
		)
	)
	(global_label "~{I3C_EXT_PU}"
		(shape input)
		(at 193.04 107.95 180)
		(fields_autoplaced yes)
		(effects
			(font
				(size 1.27 1.27)
			)
			(justify right)
		)
		(property "Intersheetrefs" "${INTERSHEET_REFS}"
			(at 179.7629 107.95 0)
			(effects
				(font
					(size 1.27 1.27)
				)
				(justify right)
			)
		)
	)
	(global_label "LOL"
		(shape input)
		(at 193.04 135.89 180)
		(fields_autoplaced yes)
		(effects
			(font
				(size 1.27 1.27)
			)
			(justify right)
		)
		(property "Intersheetrefs" "${INTERSHEET_REFS}"
			(at 187.3223 135.89 0)
			(effects
				(font
					(size 1.27 1.27)
				)
				(justify right)
			)
		)
	)
	(global_label "VIN_BULK_EN"
		(shape input)
		(at 292.1 87.63 180)
		(fields_autoplaced yes)
		(effects
			(font
				(size 1.27 1.27)
			)
			(justify right)
		)
		(property "Intersheetrefs" "${INTERSHEET_REFS}"
			(at 277.4318 87.63 0)
			(effects
				(font
					(size 1.27 1.27)
				)
				(justify right)
			)
		)
	)
	(global_label "HOT_SWAP_GREEN"
		(shape input)
		(at 292.1 82.55 180)
		(fields_autoplaced yes)
		(effects
			(font
				(size 1.27 1.27)
			)
			(justify right)
		)
		(property "Intersheetrefs" "${INTERSHEET_REFS}"
			(at 273.0239 82.4706 0)
			(effects
				(font
					(size 1.27 1.27)
				)
				(justify right)
			)
		)
	)
	(global_label "Heater_PWM"
		(shape input)
		(at 292.1 105.41 180)
		(fields_autoplaced yes)
		(effects
			(font
				(size 1.27 1.27)
			)
			(justify right)
		)
		(property "Intersheetrefs" "${INTERSHEET_REFS}"
			(at 278.46 105.41 0)
			(effects
				(font
					(size 1.27 1.27)
				)
				(justify right)
			)
		)
	)
	(global_label "VIN_MGMT_EN"
		(shape input)
		(at 292.1 95.25 180)
		(fields_autoplaced yes)
		(effects
			(font
				(size 1.27 1.27)
			)
			(justify right)
		)
		(property "Intersheetrefs" "${INTERSHEET_REFS}"
			(at 277.19 95.25 0)
			(effects
				(font
					(size 1.27 1.27)
				)
				(justify right)
			)
		)
	)
	(global_label "INT_CB"
		(shape input)
		(at 193.04 130.81 180)
		(fields_autoplaced yes)
		(effects
			(font
				(size 1.27 1.27)
			)
			(justify right)
		)
		(property "Intersheetrefs" "${INTERSHEET_REFS}"
			(at 184.2985 130.81 0)
			(effects
				(font
					(size 1.27 1.27)
				)
				(justify right)
			)
		)
	)
	(global_label "HOT_SWAP_YELLOW"
		(shape input)
		(at 292.1 77.47 180)
		(fields_autoplaced yes)
		(effects
			(font
				(size 1.27 1.27)
			)
			(justify right)
		)
		(property "Intersheetrefs" "${INTERSHEET_REFS}"
			(at 272.1168 77.3906 0)
			(effects
				(font
					(size 1.27 1.27)
				)
				(justify right)
			)
		)
	)
	(global_label "PCIE.PWRGD"
		(shape input)
		(at 82.55 130.81 180)
		(fields_autoplaced yes)
		(effects
			(font
				(size 1.27 1.27)
			)
			(justify right)
		)
		(property "Intersheetrefs" "${INTERSHEET_REFS}"
			(at 68.7958 130.8894 0)
			(effects
				(font
					(size 1.27 1.27)
				)
				(justify right)
			)
		)
	)
	(global_label "~{DDR_PRESENCE}"
		(shape input)
		(at 292.1 92.71 180)
		(fields_autoplaced yes)
		(effects
			(font
				(size 1.27 1.27)
			)
			(justify right)
		)
		(property "Intersheetrefs" "${INTERSHEET_REFS}"
			(at 275.201 92.7894 0)
			(effects
				(font
					(size 1.27 1.27)
				)
				(justify right)
			)
		)
	)
	(hierarchical_label "FPGA_PWR{I^{2}C}"
		(shape bidirectional)
		(at 288.29 128.27 180)
		(effects
			(font
				(size 1.27 1.27)
			)
			(justify right)
		)
	)
	(hierarchical_label "FPGA_DDR{I^{2}C}"
		(shape bidirectional)
		(at 288.29 118.11 180)
		(effects
			(font
				(size 1.27 1.27)
			)
			(justify right)
		)
	)
	(hierarchical_label "HDMI_CTL{I^{2}C}"
		(shape bidirectional)
		(at 154.94 107.95 180)
		(effects
			(font
				(size 1.27 1.27)
			)
			(justify right)
		)
	)
	(hierarchical_label "UART0{UART}"
		(shape bidirectional)
		(at 63.5 93.98 180)
		(effects
			(font
				(size 1.27 1.27)
			)
			(justify right)
		)
	)
	(hierarchical_label "HDMI_OUT_I2C{I^{2}C}"
		(shape bidirectional)
		(at 181.61 77.47 180)
		(effects
			(font
				(size 1.27 1.27)
			)
			(justify right)
		)
	)
	(hierarchical_label "HDMI_IN_I2C{I^{2}C}"
		(shape bidirectional)
		(at 181.61 72.39 180)
		(effects
			(font
				(size 1.27 1.27)
			)
			(justify right)
		)
	)
	(hierarchical_label "FPGA_I3C{I^{2}C}"
		(shape bidirectional)
		(at 180.34 92.71 180)
		(effects
			(font
				(size 1.27 1.27)
			)
			(justify right)
		)
	)
	(hierarchical_label "AUX{JTAG}"
		(shape bidirectional)
		(at 63.5 110.49 180)
		(effects
			(font
				(size 1.27 1.27)
			)
			(justify right)
		)
	)
	(hierarchical_label "UART1{UART}"
		(shape bidirectional)
		(at 63.5 99.06 180)
		(effects
			(font
				(size 1.27 1.27)
			)
			(justify right)
		)
	)
	(symbol
		(lib_id "antmicroResistors0402:R_330R_0402")
		(at 158.75 229.87 270)
		(unit 1)
		(exclude_from_sim no)
		(in_bom yes)
		(on_board yes)
		(dnp no)
		(fields_autoplaced yes)
		(property "Reference" "R42"
			(at 160.401 231.5794 90)
			(effects
				(font
					(size 1.27 1.27)
				)
				(justify left)
			)
		)
		(property "Value" "R_330R_0402"
			(at 146.05 250.19 0)
			(effects
				(font
					(size 1.27 1.27)
					(thickness 0.15)
				)
				(justify left bottom)
				(hide yes)
			)
		)
		(property "Footprint" "antmicro-footprints:R_0402_1005Metric"
			(at 143.51 250.19 0)
			(effects
				(font
					(size 1.27 1.27)
					(thickness 0.15)
				)
				(justify left bottom)
				(hide yes)
			)
		)
		(property "Datasheet" "https://www.bourns.com/docs/product-datasheets/cr.pdf"
			(at 140.97 250.19 0)
			(effects
				(font
					(size 1.27 1.27)
					(thickness 0.15)
				)
				(justify left bottom)
				(hide yes)
			)
		)
		(property "Description" ""
			(at 158.75 229.87 0)
			(effects
				(font
					(size 1.27 1.27)
				)
				(hide yes)
			)
		)
		(property "Manufacturer" "Bourns"
			(at 135.89 250.19 0)
			(effects
				(font
					(size 1.27 1.27)
					(thickness 0.15)
				)
				(justify left bottom)
				(hide yes)
			)
		)
		(property "MPN" "CR0402-FX-3300GLF"
			(at 138.43 250.19 0)
			(effects
				(font
					(size 1.27 1.27)
					(thickness 0.15)
				)
				(justify left bottom)
				(hide yes)
			)
		)
		(property "Val" "330R"
			(at 160.401 234.1097 90)
			(effects
				(font
					(size 1.27 1.27)
					(thickness 0.15)
				)
				(justify left)
			)
		)
		(property "License" "Apache-2.0"
			(at 133.35 250.19 0)
			(effects
				(font
					(size 1.27 1.27)
					(thickness 0.15)
				)
				(justify left bottom)
				(hide yes)
			)
		)
		(property "Author" "Antmicro"
			(at 130.81 250.19 0)
			(effects
				(font
					(size 1.27 1.27)
					(thickness 0.15)
				)
				(justify left bottom)
				(hide yes)
			)
		)
		(property "Tolerance" "1%"
			(at 148.59 250.19 0)
			(effects
				(font
					(size 1.27 1.27)
				)
				(justify left bottom)
				(hide yes)
			)
		)
		(pin "1"
		)
		(pin "2"
		)
		(instances
			(project "data-center-rdimm-ddr5-tester"
				(path ""
					(reference "R42")
					(unit 1)
				)
			)
		)
	)
	(symbol
		(lib_id "antmicropower:+3V3")
		(at 158.75 219.71 0)
		(unit 1)
		(exclude_from_sim no)
		(in_bom yes)
		(on_board yes)
		(dnp no)
		(fields_autoplaced yes)
		(property "Reference" "#PWR0430"
			(at 158.75 223.52 0)
			(effects
				(font
					(size 1.27 1.27)
				)
				(hide yes)
			)
		)
		(property "Value" "+3V3"
			(at 155.575 217.17 0)
			(effects
				(font
					(size 1.27 1.27)
					(thickness 0.15)
				)
				(justify left bottom)
			)
		)
		(property "Footprint" ""
			(at 173.99 227.33 0)
			(effects
				(font
					(size 1.27 1.27)
					(thickness 0.15)
				)
				(justify left bottom)
				(hide yes)
			)
		)
		(property "Datasheet" ""
			(at 173.99 229.87 0)
			(effects
				(font
					(size 1.27 1.27)
					(thickness 0.15)
				)
				(justify left bottom)
				(hide yes)
			)
		)
		(property "Description" ""
			(at 158.75 219.71 0)
			(effects
				(font
					(size 1.27 1.27)
				)
				(hide yes)
			)
		)
		(property "Author" "Antmicro"
			(at 173.99 222.25 0)
			(effects
				(font
					(size 1.27 1.27)
					(thickness 0.15)
				)
				(justify left bottom)
				(hide yes)
			)
		)
		(property "License" "Apache-2.0"
			(at 173.99 224.79 0)
			(effects
				(font
					(size 1.27 1.27)
					(thickness 0.15)
				)
				(justify left bottom)
				(hide yes)
			)
		)
		(pin "1"
		)
		(instances
			(project "data-center-rdimm-ddr5-tester"
				(path ""
					(reference "#PWR0430")
					(unit 1)
				)
			)
		)
	)
	(symbol
		(lib_id "antmicroTransistorsFETsMOSFETsSingle:BSS138PW")
		(at 185.42 245.11 0)
		(unit 1)
		(exclude_from_sim no)
		(in_bom yes)
		(on_board yes)
		(dnp no)
		(fields_autoplaced yes)
		(property "Reference" "Q5"
			(at 196.85 241.3 0)
			(effects
				(font
					(size 1.27 1.27)
					(thickness 0.15)
				)
				(justify left)
			)
		)
		(property "Value" "BSS138PW"
			(at 208.28 254 0)
			(effects
				(font
					(size 1.27 1.27)
					(thickness 0.15)
				)
				(justify left bottom)
				(hide yes)
			)
		)
		(property "Footprint" "antmicro-footprints:SC70-3"
			(at 208.28 256.54 0)
			(effects
				(font
					(size 1.27 1.27)
					(thickness 0.15)
				)
				(justify left bottom)
				(hide yes)
			)
		)
		(property "Datasheet" "https://assets.nexperia.com/documents/data-sheet/BSS138PW.pdf"
			(at 208.28 259.08 0)
			(effects
				(font
					(size 1.27 1.27)
					(thickness 0.15)
				)
				(justify left bottom)
				(hide yes)
			)
		)
		(property "Description" ""
			(at 185.42 245.11 0)
			(effects
				(font
					(size 1.27 1.27)
				)
				(hide yes)
			)
		)
		(property "MPN" "BSS138PW"
			(at 196.85 243.84 0)
			(effects
				(font
					(size 1.27 1.27)
					(thickness 0.15)
				)
				(justify left)
			)
		)
		(property "Manufacturer" "Nexperia"
			(at 208.28 264.16 0)
			(effects
				(font
					(size 1.27 1.27)
					(thickness 0.15)
				)
				(justify left bottom)
				(hide yes)
			)
		)
		(property "Author" "Antmicro"
			(at 208.28 266.7 0)
			(effects
				(font
					(size 1.27 1.27)
					(thickness 0.15)
				)
				(justify left bottom)
				(hide yes)
			)
		)
		(property "License" "Apache-2.0"
			(at 208.28 269.24 0)
			(effects
				(font
					(size 1.27 1.27)
					(thickness 0.15)
				)
				(justify left bottom)
				(hide yes)
			)
		)
		(pin "2"
		)
		(pin "3"
		)
		(pin "1"
		)
		(instances
			(project "data-center-rdimm-ddr5-tester"
				(path ""
					(reference "Q5")
					(unit 1)
				)
			)
		)
	)
	(symbol
		(lib_id "antmicroTransistorsFETsMOSFETsSingle:BSS138PW")
		(at 116.84 245.11 0)
		(unit 1)
		(exclude_from_sim no)
		(in_bom yes)
		(on_board yes)
		(dnp no)
		(fields_autoplaced yes)
		(property "Reference" "Q7"
			(at 128.27 241.3 0)
			(effects
				(font
					(size 1.27 1.27)
					(thickness 0.15)
				)
				(justify left)
			)
		)
		(property "Value" "BSS138PW"
			(at 139.7 254 0)
			(effects
				(font
					(size 1.27 1.27)
					(thickness 0.15)
				)
				(justify left bottom)
				(hide yes)
			)
		)
		(property "Footprint" "antmicro-footprints:SC70-3"
			(at 139.7 256.54 0)
			(effects
				(font
					(size 1.27 1.27)
					(thickness 0.15)
				)
				(justify left bottom)
				(hide yes)
			)
		)
		(property "Datasheet" "https://assets.nexperia.com/documents/data-sheet/BSS138PW.pdf"
			(at 139.7 259.08 0)
			(effects
				(font
					(size 1.27 1.27)
					(thickness 0.15)
				)
				(justify left bottom)
				(hide yes)
			)
		)
		(property "Description" ""
			(at 116.84 245.11 0)
			(effects
				(font
					(size 1.27 1.27)
				)
				(hide yes)
			)
		)
		(property "MPN" "BSS138PW"
			(at 128.27 243.84 0)
			(effects
				(font
					(size 1.27 1.27)
					(thickness 0.15)
				)
				(justify left)
			)
		)
		(property "Manufacturer" "Nexperia"
			(at 139.7 264.16 0)
			(effects
				(font
					(size 1.27 1.27)
					(thickness 0.15)
				)
				(justify left bottom)
				(hide yes)
			)
		)
		(property "Author" "Antmicro"
			(at 139.7 266.7 0)
			(effects
				(font
					(size 1.27 1.27)
					(thickness 0.15)
				)
				(justify left bottom)
				(hide yes)
			)
		)
		(property "License" "Apache-2.0"
			(at 139.7 269.24 0)
			(effects
				(font
					(size 1.27 1.27)
					(thickness 0.15)
				)
				(justify left bottom)
				(hide yes)
			)
		)
		(pin "2"
		)
		(pin "3"
		)
		(pin "1"
		)
		(instances
			(project "data-center-rdimm-ddr5-tester"
				(path ""
					(reference "Q7")
					(unit 1)
				)
			)
		)
	)
	(symbol
		(lib_id "antmicroResistors0402:R_330R_0402")
		(at 193.04 229.87 270)
		(unit 1)
		(exclude_from_sim no)
		(in_bom yes)
		(on_board yes)
		(dnp no)
		(fields_autoplaced yes)
		(property "Reference" "R41"
			(at 194.691 231.5794 90)
			(effects
				(font
					(size 1.27 1.27)
				)
				(justify left)
			)
		)
		(property "Value" "R_330R_0402"
			(at 180.34 250.19 0)
			(effects
				(font
					(size 1.27 1.27)
					(thickness 0.15)
				)
				(justify left bottom)
				(hide yes)
			)
		)
		(property "Footprint" "antmicro-footprints:R_0402_1005Metric"
			(at 177.8 250.19 0)
			(effects
				(font
					(size 1.27 1.27)
					(thickness 0.15)
				)
				(justify left bottom)
				(hide yes)
			)
		)
		(property "Datasheet" "https://www.bourns.com/docs/product-datasheets/cr.pdf"
			(at 175.26 250.19 0)
			(effects
				(font
					(size 1.27 1.27)
					(thickness 0.15)
				)
				(justify left bottom)
				(hide yes)
			)
		)
		(property "Description" ""
			(at 193.04 229.87 0)
			(effects
				(font
					(size 1.27 1.27)
				)
				(hide yes)
			)
		)
		(property "Manufacturer" "Bourns"
			(at 170.18 250.19 0)
			(effects
				(font
					(size 1.27 1.27)
					(thickness 0.15)
				)
				(justify left bottom)
				(hide yes)
			)
		)
		(property "MPN" "CR0402-FX-3300GLF"
			(at 172.72 250.19 0)
			(effects
				(font
					(size 1.27 1.27)
					(thickness 0.15)
				)
				(justify left bottom)
				(hide yes)
			)
		)
		(property "Val" "330R"
			(at 194.691 234.1097 90)
			(effects
				(font
					(size 1.27 1.27)
					(thickness 0.15)
				)
				(justify left)
			)
		)
		(property "License" "Apache-2.0"
			(at 167.64 250.19 0)
			(effects
				(font
					(size 1.27 1.27)
					(thickness 0.15)
				)
				(justify left bottom)
				(hide yes)
			)
		)
		(property "Author" "Antmicro"
			(at 165.1 250.19 0)
			(effects
				(font
					(size 1.27 1.27)
					(thickness 0.15)
				)
				(justify left bottom)
				(hide yes)
			)
		)
		(property "Tolerance" "1%"
			(at 182.88 250.19 0)
			(effects
				(font
					(size 1.27 1.27)
				)
				(justify left bottom)
				(hide yes)
			)
		)
		(pin "1"
		)
		(pin "2"
		)
		(instances
			(project "data-center-rdimm-ddr5-tester"
				(path ""
					(reference "R41")
					(unit 1)
				)
			)
		)
	)
	(symbol
		(lib_id "antmicropower:GND")
		(at 158.75 250.19 0)
		(unit 1)
		(exclude_from_sim no)
		(in_bom yes)
		(on_board yes)
		(dnp no)
		(fields_autoplaced yes)
		(property "Reference" "#PWR0431"
			(at 158.75 256.54 0)
			(effects
				(font
					(size 1.27 1.27)
				)
				(hide yes)
			)
		)
		(property "Value" "GND"
			(at 156.845 254.635 0)
			(effects
				(font
					(size 1.27 1.27)
					(thickness 0.15)
				)
				(justify left bottom)
			)
		)
		(property "Footprint" ""
			(at 167.64 257.81 0)
			(effects
				(font
					(size 1.27 1.27)
					(thickness 0.15)
				)
				(justify left bottom)
				(hide yes)
			)
		)
		(property "Datasheet" ""
			(at 167.64 262.89 0)
			(effects
				(font
					(size 1.27 1.27)
					(thickness 0.15)
				)
				(justify left bottom)
				(hide yes)
			)
		)
		(property "Description" ""
			(at 158.75 250.19 0)
			(effects
				(font
					(size 1.27 1.27)
				)
				(hide yes)
			)
		)
		(property "Author" "Antmicro"
			(at 167.64 255.27 0)
			(effects
				(font
					(size 1.27 1.27)
					(thickness 0.15)
				)
				(justify left bottom)
				(hide yes)
			)
		)
		(property "License" "Apache-2.0"
			(at 167.64 257.81 0)
			(effects
				(font
					(size 1.27 1.27)
					(thickness 0.15)
				)
				(justify left bottom)
				(hide yes)
			)
		)
		(pin "1"
		)
		(instances
			(project "data-center-rdimm-ddr5-tester"
				(path ""
					(reference "#PWR0431")
					(unit 1)
				)
			)
		)
	)
	(symbol
		(lib_id "antmicroLEDIndicationDiscrete:LED_G_0603_KP-1608CGCK")
		(at 227.33 219.71 270)
		(unit 1)
		(exclude_from_sim no)
		(in_bom yes)
		(on_board yes)
		(dnp no)
		(property "Reference" "D4"
			(at 230.378 222.6894 90)
			(effects
				(font
					(size 1.27 1.27)
				)
				(justify left)
			)
		)
		(property "Value" "LED_G_0603_KP-1608CGCK"
			(at 236.22 224.79 0)
			(effects
				(font
					(size 1.27 1.27)
					(thickness 0.15)
				)
			)
		)
		(property "Footprint" "antmicro-footprints:LED_0603_1608Metric_G"
			(at 217.17 242.57 0)
			(effects
				(font
					(size 1.27 1.27)
					(thickness 0.15)
				)
				(justify left bottom)
				(hide yes)
			)
		)
		(property "Datasheet" "http://www.kingbright.com/attachments/file/psearch//000/00/00/KP-1608CGCK(Ver.23B).pdf"
			(at 214.63 242.57 0)
			(effects
				(font
					(size 1.27 1.27)
					(thickness 0.15)
				)
				(justify left bottom)
				(hide yes)
			)
		)
		(property "Description" ""
			(at 227.33 219.71 0)
			(effects
				(font
					(size 1.27 1.27)
				)
				(hide yes)
			)
		)
		(property "MPN" "KP-1608CGCK"
			(at 230.378 225.2197 90)
			(effects
				(font
					(size 1.27 1.27)
					(thickness 0.15)
				)
				(justify left)
				(hide yes)
			)
		)
		(property "Manufacturer" "Kingbright"
			(at 209.55 242.57 0)
			(effects
				(font
					(size 1.27 1.27)
					(thickness 0.15)
				)
				(justify left bottom)
				(hide yes)
			)
		)
		(property "Author" "Antmicro"
			(at 207.01 242.57 0)
			(effects
				(font
					(size 1.27 1.27)
					(thickness 0.15)
				)
				(justify left bottom)
				(hide yes)
			)
		)
		(property "License" "Apache-2.0"
			(at 204.47 242.57 0)
			(effects
				(font
					(size 1.27 1.27)
					(thickness 0.15)
				)
				(justify left bottom)
				(hide yes)
			)
		)
		(property "Color" "Green"
			(at 222.25 242.57 0)
			(effects
				(font
					(size 1.27 1.27)
				)
				(justify left bottom)
			)
		)
		(pin "1"
		)
		(pin "2"
		)
		(instances
			(project "data-center-rdimm-ddr5-tester"
				(path ""
					(reference "D4")
					(unit 1)
				)
			)
		)
	)
	(symbol
		(lib_id "antmicroResistors0402:R_330R_0402")
		(at 124.46 229.87 270)
		(unit 1)
		(exclude_from_sim no)
		(in_bom yes)
		(on_board yes)
		(dnp no)
		(fields_autoplaced yes)
		(property "Reference" "R45"
			(at 126.111 231.5794 90)
			(effects
				(font
					(size 1.27 1.27)
				)
				(justify left)
			)
		)
		(property "Value" "R_330R_0402"
			(at 111.76 250.19 0)
			(effects
				(font
					(size 1.27 1.27)
					(thickness 0.15)
				)
				(justify left bottom)
				(hide yes)
			)
		)
		(property "Footprint" "antmicro-footprints:R_0402_1005Metric"
			(at 109.22 250.19 0)
			(effects
				(font
					(size 1.27 1.27)
					(thickness 0.15)
				)
				(justify left bottom)
				(hide yes)
			)
		)
		(property "Datasheet" "https://www.bourns.com/docs/product-datasheets/cr.pdf"
			(at 106.68 250.19 0)
			(effects
				(font
					(size 1.27 1.27)
					(thickness 0.15)
				)
				(justify left bottom)
				(hide yes)
			)
		)
		(property "Description" ""
			(at 124.46 229.87 0)
			(effects
				(font
					(size 1.27 1.27)
				)
				(hide yes)
			)
		)
		(property "Manufacturer" "Bourns"
			(at 101.6 250.19 0)
			(effects
				(font
					(size 1.27 1.27)
					(thickness 0.15)
				)
				(justify left bottom)
				(hide yes)
			)
		)
		(property "MPN" "CR0402-FX-3300GLF"
			(at 104.14 250.19 0)
			(effects
				(font
					(size 1.27 1.27)
					(thickness 0.15)
				)
				(justify left bottom)
				(hide yes)
			)
		)
		(property "Val" "330R"
			(at 126.111 234.1097 90)
			(effects
				(font
					(size 1.27 1.27)
					(thickness 0.15)
				)
				(justify left)
			)
		)
		(property "License" "Apache-2.0"
			(at 99.06 250.19 0)
			(effects
				(font
					(size 1.27 1.27)
					(thickness 0.15)
				)
				(justify left bottom)
				(hide yes)
			)
		)
		(property "Author" "Antmicro"
			(at 96.52 250.19 0)
			(effects
				(font
					(size 1.27 1.27)
					(thickness 0.15)
				)
				(justify left bottom)
				(hide yes)
			)
		)
		(property "Tolerance" "1%"
			(at 114.3 250.19 0)
			(effects
				(font
					(size 1.27 1.27)
				)
				(justify left bottom)
				(hide yes)
			)
		)
		(pin "1"
		)
		(pin "2"
		)
		(instances
			(project "data-center-rdimm-ddr5-tester"
				(path ""
					(reference "R45")
					(unit 1)
				)
			)
		)
	)
	(symbol
		(lib_id "antmicroLEDIndicationDiscrete:LED_G_0603_KP-1608CGCK")
		(at 193.04 220.98 270)
		(unit 1)
		(exclude_from_sim no)
		(in_bom yes)
		(on_board yes)
		(dnp no)
		(property "Reference" "D5"
			(at 196.088 223.9594 90)
			(effects
				(font
					(size 1.27 1.27)
				)
				(justify left)
			)
		)
		(property "Value" "LED_G_0603_KP-1608CGCK"
			(at 201.93 224.79 0)
			(effects
				(font
					(size 1.27 1.27)
					(thickness 0.15)
				)
			)
		)
		(property "Footprint" "antmicro-footprints:LED_0603_1608Metric_G"
			(at 182.88 243.84 0)
			(effects
				(font
					(size 1.27 1.27)
					(thickness 0.15)
				)
				(justify left bottom)
				(hide yes)
			)
		)
		(property "Datasheet" "http://www.kingbright.com/attachments/file/psearch//000/00/00/KP-1608CGCK(Ver.23B).pdf"
			(at 180.34 243.84 0)
			(effects
				(font
					(size 1.27 1.27)
					(thickness 0.15)
				)
				(justify left bottom)
				(hide yes)
			)
		)
		(property "Description" ""
			(at 193.04 220.98 0)
			(effects
				(font
					(size 1.27 1.27)
				)
				(hide yes)
			)
		)
		(property "MPN" "KP-1608CGCK"
			(at 196.088 226.4897 90)
			(effects
				(font
					(size 1.27 1.27)
					(thickness 0.15)
				)
				(justify left)
				(hide yes)
			)
		)
		(property "Manufacturer" "Kingbright"
			(at 175.26 243.84 0)
			(effects
				(font
					(size 1.27 1.27)
					(thickness 0.15)
				)
				(justify left bottom)
				(hide yes)
			)
		)
		(property "Author" "Antmicro"
			(at 172.72 243.84 0)
			(effects
				(font
					(size 1.27 1.27)
					(thickness 0.15)
				)
				(justify left bottom)
				(hide yes)
			)
		)
		(property "License" "Apache-2.0"
			(at 170.18 243.84 0)
			(effects
				(font
					(size 1.27 1.27)
					(thickness 0.15)
				)
				(justify left bottom)
				(hide yes)
			)
		)
		(property "Color" "Green"
			(at 187.96 243.84 0)
			(effects
				(font
					(size 1.27 1.27)
				)
				(justify left bottom)
			)
		)
		(pin "1"
		)
		(pin "2"
		)
		(instances
			(project "data-center-rdimm-ddr5-tester"
				(path ""
					(reference "D5")
					(unit 1)
				)
			)
		)
	)
	(symbol
		(lib_id "antmicroLEDIndicationDiscrete:LED_G_0603_KP-1608CGCK")
		(at 124.46 220.98 270)
		(unit 1)
		(exclude_from_sim no)
		(in_bom yes)
		(on_board yes)
		(dnp no)
		(property "Reference" "D7"
			(at 127.508 223.9594 90)
			(effects
				(font
					(size 1.27 1.27)
				)
				(justify left)
			)
		)
		(property "Value" "LED_G_0603_KP-1608CGCK"
			(at 133.35 224.79 0)
			(effects
				(font
					(size 1.27 1.27)
					(thickness 0.15)
				)
			)
		)
		(property "Footprint" "antmicro-footprints:LED_0603_1608Metric_G"
			(at 114.3 243.84 0)
			(effects
				(font
					(size 1.27 1.27)
					(thickness 0.15)
				)
				(justify left bottom)
				(hide yes)
			)
		)
		(property "Datasheet" "http://www.kingbright.com/attachments/file/psearch//000/00/00/KP-1608CGCK(Ver.23B).pdf"
			(at 111.76 243.84 0)
			(effects
				(font
					(size 1.27 1.27)
					(thickness 0.15)
				)
				(justify left bottom)
				(hide yes)
			)
		)
		(property "Description" ""
			(at 124.46 220.98 0)
			(effects
				(font
					(size 1.27 1.27)
				)
				(hide yes)
			)
		)
		(property "MPN" "KP-1608CGCK"
			(at 127.508 226.4897 90)
			(effects
				(font
					(size 1.27 1.27)
					(thickness 0.15)
				)
				(justify left)
				(hide yes)
			)
		)
		(property "Manufacturer" "Kingbright"
			(at 106.68 243.84 0)
			(effects
				(font
					(size 1.27 1.27)
					(thickness 0.15)
				)
				(justify left bottom)
				(hide yes)
			)
		)
		(property "Author" "Antmicro"
			(at 104.14 243.84 0)
			(effects
				(font
					(size 1.27 1.27)
					(thickness 0.15)
				)
				(justify left bottom)
				(hide yes)
			)
		)
		(property "License" "Apache-2.0"
			(at 101.6 243.84 0)
			(effects
				(font
					(size 1.27 1.27)
					(thickness 0.15)
				)
				(justify left bottom)
				(hide yes)
			)
		)
		(property "Color" "Green"
			(at 119.38 243.84 0)
			(effects
				(font
					(size 1.27 1.27)
				)
				(justify left bottom)
			)
		)
		(pin "1"
		)
		(pin "2"
		)
		(instances
			(project "data-center-rdimm-ddr5-tester"
				(path ""
					(reference "D7")
					(unit 1)
				)
			)
		)
	)
	(symbol
		(lib_id "antmicropower:GND")
		(at 227.33 250.19 0)
		(unit 1)
		(exclude_from_sim no)
		(in_bom yes)
		(on_board yes)
		(dnp no)
		(fields_autoplaced yes)
		(property "Reference" "#PWR0427"
			(at 227.33 256.54 0)
			(effects
				(font
					(size 1.27 1.27)
				)
				(hide yes)
			)
		)
		(property "Value" "GND"
			(at 225.425 254.635 0)
			(effects
				(font
					(size 1.27 1.27)
					(thickness 0.15)
				)
				(justify left bottom)
			)
		)
		(property "Footprint" ""
			(at 236.22 257.81 0)
			(effects
				(font
					(size 1.27 1.27)
					(thickness 0.15)
				)
				(justify left bottom)
				(hide yes)
			)
		)
		(property "Datasheet" ""
			(at 236.22 262.89 0)
			(effects
				(font
					(size 1.27 1.27)
					(thickness 0.15)
				)
				(justify left bottom)
				(hide yes)
			)
		)
		(property "Description" ""
			(at 227.33 250.19 0)
			(effects
				(font
					(size 1.27 1.27)
				)
				(hide yes)
			)
		)
		(property "Author" "Antmicro"
			(at 236.22 255.27 0)
			(effects
				(font
					(size 1.27 1.27)
					(thickness 0.15)
				)
				(justify left bottom)
				(hide yes)
			)
		)
		(property "License" "Apache-2.0"
			(at 236.22 257.81 0)
			(effects
				(font
					(size 1.27 1.27)
					(thickness 0.15)
				)
				(justify left bottom)
				(hide yes)
			)
		)
		(pin "1"
		)
		(instances
			(project "data-center-rdimm-ddr5-tester"
				(path ""
					(reference "#PWR0427")
					(unit 1)
				)
			)
		)
	)
	(symbol
		(lib_id "antmicropower:GND")
		(at 193.04 250.19 0)
		(unit 1)
		(exclude_from_sim no)
		(in_bom yes)
		(on_board yes)
		(dnp no)
		(fields_autoplaced yes)
		(property "Reference" "#PWR0429"
			(at 193.04 256.54 0)
			(effects
				(font
					(size 1.27 1.27)
				)
				(hide yes)
			)
		)
		(property "Value" "GND"
			(at 191.135 254.635 0)
			(effects
				(font
					(size 1.27 1.27)
					(thickness 0.15)
				)
				(justify left bottom)
			)
		)
		(property "Footprint" ""
			(at 201.93 257.81 0)
			(effects
				(font
					(size 1.27 1.27)
					(thickness 0.15)
				)
				(justify left bottom)
				(hide yes)
			)
		)
		(property "Datasheet" ""
			(at 201.93 262.89 0)
			(effects
				(font
					(size 1.27 1.27)
					(thickness 0.15)
				)
				(justify left bottom)
				(hide yes)
			)
		)
		(property "Description" ""
			(at 193.04 250.19 0)
			(effects
				(font
					(size 1.27 1.27)
				)
				(hide yes)
			)
		)
		(property "Author" "Antmicro"
			(at 201.93 255.27 0)
			(effects
				(font
					(size 1.27 1.27)
					(thickness 0.15)
				)
				(justify left bottom)
				(hide yes)
			)
		)
		(property "License" "Apache-2.0"
			(at 201.93 257.81 0)
			(effects
				(font
					(size 1.27 1.27)
					(thickness 0.15)
				)
				(justify left bottom)
				(hide yes)
			)
		)
		(pin "1"
		)
		(instances
			(project "data-center-rdimm-ddr5-tester"
				(path ""
					(reference "#PWR0429")
					(unit 1)
				)
			)
		)
	)
	(symbol
		(lib_id "antmicroResistors0402:R_330R_0402")
		(at 227.33 228.6 270)
		(unit 1)
		(exclude_from_sim no)
		(in_bom yes)
		(on_board yes)
		(dnp no)
		(fields_autoplaced yes)
		(property "Reference" "R40"
			(at 228.981 230.3094 90)
			(effects
				(font
					(size 1.27 1.27)
				)
				(justify left)
			)
		)
		(property "Value" "R_330R_0402"
			(at 214.63 248.92 0)
			(effects
				(font
					(size 1.27 1.27)
					(thickness 0.15)
				)
				(justify left bottom)
				(hide yes)
			)
		)
		(property "Footprint" "antmicro-footprints:R_0402_1005Metric"
			(at 212.09 248.92 0)
			(effects
				(font
					(size 1.27 1.27)
					(thickness 0.15)
				)
				(justify left bottom)
				(hide yes)
			)
		)
		(property "Datasheet" "https://www.bourns.com/docs/product-datasheets/cr.pdf"
			(at 209.55 248.92 0)
			(effects
				(font
					(size 1.27 1.27)
					(thickness 0.15)
				)
				(justify left bottom)
				(hide yes)
			)
		)
		(property "Description" ""
			(at 227.33 228.6 0)
			(effects
				(font
					(size 1.27 1.27)
				)
				(hide yes)
			)
		)
		(property "Manufacturer" "Bourns"
			(at 204.47 248.92 0)
			(effects
				(font
					(size 1.27 1.27)
					(thickness 0.15)
				)
				(justify left bottom)
				(hide yes)
			)
		)
		(property "MPN" "CR0402-FX-3300GLF"
			(at 207.01 248.92 0)
			(effects
				(font
					(size 1.27 1.27)
					(thickness 0.15)
				)
				(justify left bottom)
				(hide yes)
			)
		)
		(property "Val" "330R"
			(at 228.981 232.8397 90)
			(effects
				(font
					(size 1.27 1.27)
					(thickness 0.15)
				)
				(justify left)
			)
		)
		(property "License" "Apache-2.0"
			(at 201.93 248.92 0)
			(effects
				(font
					(size 1.27 1.27)
					(thickness 0.15)
				)
				(justify left bottom)
				(hide yes)
			)
		)
		(property "Author" "Antmicro"
			(at 199.39 248.92 0)
			(effects
				(font
					(size 1.27 1.27)
					(thickness 0.15)
				)
				(justify left bottom)
				(hide yes)
			)
		)
		(property "Tolerance" "1%"
			(at 217.17 248.92 0)
			(effects
				(font
					(size 1.27 1.27)
				)
				(justify left bottom)
				(hide yes)
			)
		)
		(pin "1"
		)
		(pin "2"
		)
		(instances
			(project "data-center-rdimm-ddr5-tester"
				(path ""
					(reference "R40")
					(unit 1)
				)
			)
		)
	)
	(symbol
		(lib_id "antmicropower:+3V3")
		(at 86.36 219.71 0)
		(unit 1)
		(exclude_from_sim no)
		(in_bom yes)
		(on_board yes)
		(dnp no)
		(fields_autoplaced yes)
		(property "Reference" "#PWR0434"
			(at 86.36 223.52 0)
			(effects
				(font
					(size 1.27 1.27)
				)
				(hide yes)
			)
		)
		(property "Value" "+3V3"
			(at 83.185 217.17 0)
			(effects
				(font
					(size 1.27 1.27)
					(thickness 0.15)
				)
				(justify left bottom)
			)
		)
		(property "Footprint" ""
			(at 101.6 227.33 0)
			(effects
				(font
					(size 1.27 1.27)
					(thickness 0.15)
				)
				(justify left bottom)
				(hide yes)
			)
		)
		(property "Datasheet" ""
			(at 101.6 229.87 0)
			(effects
				(font
					(size 1.27 1.27)
					(thickness 0.15)
				)
				(justify left bottom)
				(hide yes)
			)
		)
		(property "Description" ""
			(at 86.36 219.71 0)
			(effects
				(font
					(size 1.27 1.27)
				)
				(hide yes)
			)
		)
		(property "Author" "Antmicro"
			(at 101.6 222.25 0)
			(effects
				(font
					(size 1.27 1.27)
					(thickness 0.15)
				)
				(justify left bottom)
				(hide yes)
			)
		)
		(property "License" "Apache-2.0"
			(at 101.6 224.79 0)
			(effects
				(font
					(size 1.27 1.27)
					(thickness 0.15)
				)
				(justify left bottom)
				(hide yes)
			)
		)
		(pin "1"
		)
		(instances
			(project "data-center-rdimm-ddr5-tester"
				(path ""
					(reference "#PWR0434")
					(unit 1)
				)
			)
		)
	)
	(symbol
		(lib_id "antmicropower:+3V3")
		(at 317.5 64.77 0)
		(unit 1)
		(exclude_from_sim no)
		(in_bom yes)
		(on_board yes)
		(dnp no)
		(fields_autoplaced yes)
		(property "Reference" "#PWR0145"
			(at 317.5 68.58 0)
			(effects
				(font
					(size 1.27 1.27)
				)
				(hide yes)
			)
		)
		(property "Value" "+3V3"
			(at 314.325 62.23 0)
			(effects
				(font
					(size 1.27 1.27)
					(thickness 0.15)
				)
				(justify left bottom)
			)
		)
		(property "Footprint" ""
			(at 332.74 72.39 0)
			(effects
				(font
					(size 1.27 1.27)
					(thickness 0.15)
				)
				(justify left bottom)
				(hide yes)
			)
		)
		(property "Datasheet" ""
			(at 332.74 74.93 0)
			(effects
				(font
					(size 1.27 1.27)
					(thickness 0.15)
				)
				(justify left bottom)
				(hide yes)
			)
		)
		(property "Description" ""
			(at 317.5 64.77 0)
			(effects
				(font
					(size 1.27 1.27)
				)
				(hide yes)
			)
		)
		(property "Author" "Antmicro"
			(at 332.74 67.31 0)
			(effects
				(font
					(size 1.27 1.27)
					(thickness 0.15)
				)
				(justify left bottom)
				(hide yes)
			)
		)
		(property "License" "Apache-2.0"
			(at 332.74 69.85 0)
			(effects
				(font
					(size 1.27 1.27)
					(thickness 0.15)
				)
				(justify left bottom)
				(hide yes)
			)
		)
		(pin "1"
		)
		(instances
			(project "data-center-rdimm-ddr5-tester"
				(path ""
					(reference "#PWR0145")
					(unit 1)
				)
			)
		)
	)
	(symbol
		(lib_id "antmicropower:+3V3")
		(at 90.17 66.04 0)
		(unit 1)
		(exclude_from_sim no)
		(in_bom yes)
		(on_board yes)
		(dnp no)
		(fields_autoplaced yes)
		(property "Reference" "#PWR0153"
			(at 90.17 69.85 0)
			(effects
				(font
					(size 1.27 1.27)
				)
				(hide yes)
			)
		)
		(property "Value" "+3V3"
			(at 86.995 63.5 0)
			(effects
				(font
					(size 1.27 1.27)
					(thickness 0.15)
				)
				(justify left bottom)
			)
		)
		(property "Footprint" ""
			(at 105.41 73.66 0)
			(effects
				(font
					(size 1.27 1.27)
					(thickness 0.15)
				)
				(justify left bottom)
				(hide yes)
			)
		)
		(property "Datasheet" ""
			(at 105.41 76.2 0)
			(effects
				(font
					(size 1.27 1.27)
					(thickness 0.15)
				)
				(justify left bottom)
				(hide yes)
			)
		)
		(property "Description" ""
			(at 90.17 66.04 0)
			(effects
				(font
					(size 1.27 1.27)
				)
				(hide yes)
			)
		)
		(property "Author" "Antmicro"
			(at 105.41 68.58 0)
			(effects
				(font
					(size 1.27 1.27)
					(thickness 0.15)
				)
				(justify left bottom)
				(hide yes)
			)
		)
		(property "License" "Apache-2.0"
			(at 105.41 71.12 0)
			(effects
				(font
					(size 1.27 1.27)
					(thickness 0.15)
				)
				(justify left bottom)
				(hide yes)
			)
		)
		(pin "1"
		)
		(instances
			(project "data-center-rdimm-ddr5-tester"
				(path ""
					(reference "#PWR0153")
					(unit 1)
				)
			)
		)
	)
	(symbol
		(lib_id "antmicroLEDIndicationDiscrete:LED_G_0603_KP-1608CGCK")
		(at 86.36 220.98 270)
		(unit 1)
		(exclude_from_sim no)
		(in_bom yes)
		(on_board yes)
		(dnp no)
		(property "Reference" "D8"
			(at 89.408 223.9594 90)
			(effects
				(font
					(size 1.27 1.27)
				)
				(justify left)
			)
		)
		(property "Value" "LED_G_0603_KP-1608CGCK"
			(at 94.615 224.79 0)
			(effects
				(font
					(size 1.27 1.27)
					(thickness 0.15)
				)
			)
		)
		(property "Footprint" "antmicro-footprints:LED_0603_1608Metric_G"
			(at 76.2 243.84 0)
			(effects
				(font
					(size 1.27 1.27)
					(thickness 0.15)
				)
				(justify left bottom)
				(hide yes)
			)
		)
		(property "Datasheet" "http://www.kingbright.com/attachments/file/psearch//000/00/00/KP-1608CGCK(Ver.23B).pdf"
			(at 73.66 243.84 0)
			(effects
				(font
					(size 1.27 1.27)
					(thickness 0.15)
				)
				(justify left bottom)
				(hide yes)
			)
		)
		(property "Description" ""
			(at 86.36 220.98 0)
			(effects
				(font
					(size 1.27 1.27)
				)
				(hide yes)
			)
		)
		(property "MPN" "KP-1608CGCK"
			(at 89.408 226.4897 90)
			(effects
				(font
					(size 1.27 1.27)
					(thickness 0.15)
				)
				(justify left)
				(hide yes)
			)
		)
		(property "Manufacturer" "Kingbright"
			(at 68.58 243.84 0)
			(effects
				(font
					(size 1.27 1.27)
					(thickness 0.15)
				)
				(justify left bottom)
				(hide yes)
			)
		)
		(property "Author" "Antmicro"
			(at 66.04 243.84 0)
			(effects
				(font
					(size 1.27 1.27)
					(thickness 0.15)
				)
				(justify left bottom)
				(hide yes)
			)
		)
		(property "License" "Apache-2.0"
			(at 63.5 243.84 0)
			(effects
				(font
					(size 1.27 1.27)
					(thickness 0.15)
				)
				(justify left bottom)
				(hide yes)
			)
		)
		(property "Color" "Green"
			(at 81.28 243.84 0)
			(effects
				(font
					(size 1.27 1.27)
				)
				(justify left bottom)
			)
		)
		(pin "1"
		)
		(pin "2"
		)
		(instances
			(project "data-center-rdimm-ddr5-tester"
				(path ""
					(reference "D8")
					(unit 1)
				)
			)
		)
	)
	(symbol
		(lib_id "antmicroLEDIndicationDiscrete:LED_G_0603_KP-1608CGCK")
		(at 158.75 220.98 270)
		(unit 1)
		(exclude_from_sim no)
		(in_bom yes)
		(on_board yes)
		(dnp no)
		(property "Reference" "D6"
			(at 161.798 223.9594 90)
			(effects
				(font
					(size 1.27 1.27)
				)
				(justify left)
			)
		)
		(property "Value" "LED_G_0603_KP-1608CGCK"
			(at 167.64 224.79 0)
			(effects
				(font
					(size 1.27 1.27)
					(thickness 0.15)
				)
			)
		)
		(property "Footprint" "antmicro-footprints:LED_0603_1608Metric_G"
			(at 148.59 243.84 0)
			(effects
				(font
					(size 1.27 1.27)
					(thickness 0.15)
				)
				(justify left bottom)
				(hide yes)
			)
		)
		(property "Datasheet" "http://www.kingbright.com/attachments/file/psearch//000/00/00/KP-1608CGCK(Ver.23B).pdf"
			(at 146.05 243.84 0)
			(effects
				(font
					(size 1.27 1.27)
					(thickness 0.15)
				)
				(justify left bottom)
				(hide yes)
			)
		)
		(property "Description" ""
			(at 158.75 220.98 0)
			(effects
				(font
					(size 1.27 1.27)
				)
				(hide yes)
			)
		)
		(property "MPN" "KP-1608CGCK"
			(at 161.798 226.4897 90)
			(effects
				(font
					(size 1.27 1.27)
					(thickness 0.15)
				)
				(justify left)
				(hide yes)
			)
		)
		(property "Manufacturer" "Kingbright"
			(at 140.97 243.84 0)
			(effects
				(font
					(size 1.27 1.27)
					(thickness 0.15)
				)
				(justify left bottom)
				(hide yes)
			)
		)
		(property "Author" "Antmicro"
			(at 138.43 243.84 0)
			(effects
				(font
					(size 1.27 1.27)
					(thickness 0.15)
				)
				(justify left bottom)
				(hide yes)
			)
		)
		(property "License" "Apache-2.0"
			(at 135.89 243.84 0)
			(effects
				(font
					(size 1.27 1.27)
					(thickness 0.15)
				)
				(justify left bottom)
				(hide yes)
			)
		)
		(property "Color" "Green"
			(at 153.67 243.84 0)
			(effects
				(font
					(size 1.27 1.27)
				)
				(justify left bottom)
			)
		)
		(pin "1"
		)
		(pin "2"
		)
		(instances
			(project "data-center-rdimm-ddr5-tester"
				(path ""
					(reference "D6")
					(unit 1)
				)
			)
		)
	)
	(symbol
		(lib_name "XCAU25P-2FFVB676I_1")
		(lib_id "antmicroFPGAChips:XCAU25P-2FFVB676I")
		(at 205.74 72.39 0)
		(unit 8)
		(exclude_from_sim no)
		(in_bom yes)
		(on_board yes)
		(dnp no)
		(property "Reference" "U34"
			(at 210.82 66.04 0)
			(effects
				(font
					(size 1.27 1.27)
					(thickness 0.15)
				)
				(justify left)
			)
		)
		(property "Value" "XCAU25P-2FFVB676I"
			(at 269.24 77.47 0)
			(effects
				(font
					(size 1.27 1.27)
					(thickness 0.15)
				)
				(justify left bottom)
				(hide yes)
			)
		)
		(property "Footprint" "antmicro-footprints:BGA-676_27x27mm_Layout26x26_P1x1mm_FFVB676"
			(at 269.24 80.01 0)
			(effects
				(font
					(size 1.27 1.27)
					(thickness 0.15)
				)
				(justify left bottom)
				(hide yes)
			)
		)
		(property "Datasheet" "https://docs.xilinx.com/viewer/book-attachment/2PXOpPtpaABIt0fkzeBLnw/hvbsEUaOT0OxFhln7VEVyA"
			(at 269.24 82.55 0)
			(effects
				(font
					(size 1.27 1.27)
					(thickness 0.15)
				)
				(justify left bottom)
				(hide yes)
			)
		)
		(property "Description" ""
			(at 205.74 72.39 0)
			(effects
				(font
					(size 1.27 1.27)
				)
				(hide yes)
			)
		)
		(property "MPN" "XCAU25P-2FFVB676I"
			(at 210.82 68.58 0)
			(effects
				(font
					(size 1.27 1.27)
					(thickness 0.15)
				)
				(justify left)
			)
		)
		(property "Manufacturer" "AMD-Xilinx"
			(at 269.24 85.09 0)
			(effects
				(font
					(size 1.27 1.27)
					(thickness 0.15)
				)
				(justify left bottom)
				(hide yes)
			)
		)
		(property "Author" "Antmicro"
			(at 269.24 87.63 0)
			(effects
				(font
					(size 1.27 1.27)
					(thickness 0.15)
				)
				(justify left bottom)
				(hide yes)
			)
		)
		(property "License" "Apache-2.0"
			(at 269.24 90.17 0)
			(effects
				(font
					(size 1.27 1.27)
					(thickness 0.15)
				)
				(justify left bottom)
				(hide yes)
			)
		)
		(pin "AC23"
		)
		(pin "P20"
		)
		(pin "N19"
		)
		(pin "AA24"
		)
		(pin "J16"
		)
		(pin "J21"
		)
		(pin "AE10"
		)
		(pin "F6"
		)
		(pin "F7"
		)
		(pin "AF17"
		)
		(pin "AA15"
		)
		(pin "J25"
		)
		(pin "Y21"
		)
		(pin "AA7"
		)
		(pin "E26"
		)
		(pin "AD16"
		)
		(pin "V1"
		)
		(pin "AB14"
		)
		(pin "Y1"
		)
		(pin "E24"
		)
		(pin "AA14"
		)
		(pin "J20"
		)
		(pin "U25"
		)
		(pin "AE18"
		)
		(pin "U22"
		)
		(pin "P4"
		)
		(pin "P5"
		)
		(pin "R1"
		)
		(pin "R10"
		)
		(pin "P8"
		)
		(pin "P9"
		)
		(pin "R11"
		)
		(pin "R12"
		)
		(pin "AD3"
		)
		(pin "AD9"
		)
		(pin "AD4"
		)
		(pin "P18"
		)
		(pin "P3"
		)
		(pin "G14"
		)
		(pin "AE26"
		)
		(pin "B12"
		)
		(pin "AC2"
		)
		(pin "W7"
		)
		(pin "W8"
		)
		(pin "W11"
		)
		(pin "W17"
		)
		(pin "W2"
		)
		(pin "W22"
		)
		(pin "W3"
		)
		(pin "W6"
		)
		(pin "P6"
		)
		(pin "U26"
		)
		(pin "P19"
		)
		(pin "U1"
		)
		(pin "U10"
		)
		(pin "J15"
		)
		(pin "AB25"
		)
		(pin "L23"
		)
		(pin "P24"
		)
		(pin "G16"
		)
		(pin "C10"
		)
		(pin "F14"
		)
		(pin "U24"
		)
		(pin "Y24"
		)
		(pin "Y11"
		)
		(pin "J26"
		)
		(pin "AB4"
		)
		(pin "AD18"
		)
		(pin "J24"
		)
		(pin "AF2"
		)
		(pin "B26"
		)
		(pin "U6"
		)
		(pin "U7"
		)
		(pin "M11"
		)
		(pin "M12"
		)
		(pin "T20"
		)
		(pin "V23"
		)
		(pin "AD10"
		)
		(pin "D1"
		)
		(pin "AF1"
		)
		(pin "C8"
		)
		(pin "U13"
		)
		(pin "U14"
		)
		(pin "AD19"
		)
		(pin "Y4"
		)
		(pin "Y5"
		)
		(pin "E23"
		)
		(pin "C6"
		)
		(pin "AE14"
		)
		(pin "D22"
		)
		(pin "C20"
		)
		(pin "AB17"
		)
		(pin "AD24"
		)
		(pin "L1"
		)
		(pin "L10"
		)
		(pin "AE3"
		)
		(pin "G21"
		)
		(pin "AA17"
		)
		(pin "D6"
		)
		(pin "M25"
		)
		(pin "R17"
		)
		(pin "R18"
		)
		(pin "AE15"
		)
		(pin "H7"
		)
		(pin "H8"
		)
		(pin "R6"
		)
		(pin "R7"
		)
		(pin "AB20"
		)
		(pin "C5"
		)
		(pin "Y14"
		)
		(pin "AE13"
		)
		(pin "C13"
		)
		(pin "W4"
		)
		(pin "P22"
		)
		(pin "AF6"
		)
		(pin "B8"
		)
		(pin "AF18"
		)
		(pin "G22"
		)
		(pin "J2"
		)
		(pin "J3"
		)
		(pin "L3"
		)
		(pin "L6"
		)
		(pin "P12"
		)
		(pin "P15"
		)
		(pin "Y12"
		)
		(pin "K18"
		)
		(pin "V10"
		)
		(pin "V11"
		)
		(pin "D7"
		)
		(pin "D8"
		)
		(pin "P23"
		)
		(pin "AA3"
		)
		(pin "AB18"
		)
		(pin "H18"
		)
		(pin "B6"
		)
		(pin "R24"
		)
		(pin "R3"
		)
		(pin "P16"
		)
		(pin "P17"
		)
		(pin "AF23"
		)
		(pin "AC14"
		)
		(pin "M6"
		)
		(pin "B18"
		)
		(pin "M1"
		)
		(pin "B5"
		)
		(pin "D2"
		)
		(pin "G20"
		)
		(pin "M2"
		)
		(pin "B4"
		)
		(pin "AA16"
		)
		(pin "V9"
		)
		(pin "W1"
		)
		(pin "N5"
		)
		(pin "AA26"
		)
		(pin "B3"
		)
		(pin "D12"
		)
		(pin "N4"
		)
		(pin "AA2"
		)
		(pin "B23"
		)
		(pin "C12"
		)
		(pin "L5"
		)
		(pin "AA6"
		)
		(pin "B1"
		)
		(pin "H1"
		)
		(pin "A14"
		)
		(pin "A13"
		)
		(pin "AB2"
		)
		(pin "AE4"
		)
		(pin "Y16"
		)
		(pin "B24"
		)
		(pin "H16"
		)
		(pin "W24"
		)
		(pin "D18"
		)
		(pin "B20"
		)
		(pin "D21"
		)
		(pin "B19"
		)
		(pin "B25"
		)
		(pin "C24"
		)
		(pin "A15"
		)
		(pin "M26"
		)
		(pin "A23"
		)
		(pin "C17"
		)
		(pin "K21"
		)
		(pin "W23"
		)
		(pin "L24"
		)
		(pin "R20"
		)
		(pin "C21"
		)
		(pin "D24"
		)
		(pin "E15"
		)
		(pin "AD12"
		)
		(pin "D23"
		)
		(pin "D25"
		)
		(pin "C26"
		)
		(pin "B21"
		)
		(pin "Y26"
		)
		(pin "AE25"
		)
		(pin "C19"
		)
		(pin "C23"
		)
		(pin "P21"
		)
		(pin "A20"
		)
		(pin "L18"
		)
		(pin "A25"
		)
		(pin "K23"
		)
		(pin "V18"
		)
		(pin "C16"
		)
		(pin "V21"
		)
		(pin "E17"
		)
		(pin "A17"
		)
		(pin "P25"
		)
		(pin "AD25"
		)
		(pin "G18"
		)
		(pin "AB3"
		)
		(pin "J6"
		)
		(pin "J7"
		)
		(pin "K12"
		)
		(pin "K13"
		)
		(pin "AB16"
		)
		(pin "C1"
		)
		(pin "AF15"
		)
		(pin "J8"
		)
		(pin "K11"
		)
		(pin "AD1"
		)
		(pin "F25"
		)
		(pin "AE1"
		)
		(pin "V2"
		)
		(pin "U2"
		)
		(pin "U3"
		)
		(pin "F2"
		)
		(pin "V6"
		)
		(pin "P1"
		)
		(pin "L13"
		)
		(pin "L14"
		)
		(pin "AD5"
		)
		(pin "AE8"
		)
		(pin "AB10"
		)
		(pin "U15"
		)
		(pin "U16"
		)
		(pin "U17"
		)
		(pin "U18"
		)
		(pin "D26"
		)
		(pin "G5"
		)
		(pin "E25"
		)
		(pin "AD22"
		)
		(pin "A19"
		)
		(pin "P7"
		)
		(pin "Y2"
		)
		(pin "J22"
		)
		(pin "Y19"
		)
		(pin "Y3"
		)
		(pin "AB7"
		)
		(pin "AF22"
		)
		(pin "B2"
		)
		(pin "AA10"
		)
		(pin "V7"
		)
		(pin "V22"
		)
		(pin "J23"
		)
		(pin "AF12"
		)
		(pin "V16"
		)
		(pin "V17"
		)
		(pin "Y7"
		)
		(pin "D15"
		)
		(pin "H12"
		)
		(pin "AF7"
		)
		(pin "U23"
		)
		(pin "V19"
		)
		(pin "AF14"
		)
		(pin "AF13"
		)
		(pin "G8"
		)
		(pin "H20"
		)
		(pin "U11"
		)
		(pin "U12"
		)
		(pin "A5"
		)
		(pin "G6"
		)
		(pin "G7"
		)
		(pin "L15"
		)
		(pin "L16"
		)
		(pin "T8"
		)
		(pin "T9"
		)
		(pin "G19"
		)
		(pin "G17"
		)
		(pin "T4"
		)
		(pin "T5"
		)
		(pin "B13"
		)
		(pin "G23"
		)
		(pin "G3"
		)
		(pin "T26"
		)
		(pin "T3"
		)
		(pin "G13"
		)
		(pin "G2"
		)
		(pin "D17"
		)
		(pin "AD15"
		)
		(pin "Y8"
		)
		(pin "Y9"
		)
		(pin "AC24"
		)
		(pin "AD8"
		)
		(pin "F8"
		)
		(pin "G1"
		)
		(pin "AD6"
		)
		(pin "F18"
		)
		(pin "H17"
		)
		(pin "AA13"
		)
		(pin "K20"
		)
		(pin "AD7"
		)
		(pin "AA1"
		)
		(pin "AF19"
		)
		(pin "Y15"
		)
		(pin "AB13"
		)
		(pin "N13"
		)
		(pin "N14"
		)
		(pin "V14"
		)
		(pin "V15"
		)
		(pin "U8"
		)
		(pin "U9"
		)
		(pin "W13"
		)
		(pin "V5"
		)
		(pin "V8"
		)
		(pin "W5"
		)
		(pin "P26"
		)
		(pin "Y20"
		)
		(pin "L17"
		)
		(pin "L2"
		)
		(pin "H26"
		)
		(pin "Y6"
		)
		(pin "AC22"
		)
		(pin "D13"
		)
		(pin "V12"
		)
		(pin "V13"
		)
		(pin "AE9"
		)
		(pin "B7"
		)
		(pin "A11"
		)
		(pin "K9"
		)
		(pin "L11"
		)
		(pin "L12"
		)
		(pin "H5"
		)
		(pin "H6"
		)
		(pin "AE19"
		)
		(pin "C18"
		)
		(pin "H13"
		)
		(pin "AB23"
		)
		(pin "AC26"
		)
		(pin "R19"
		)
		(pin "R2"
		)
		(pin "H19"
		)
		(pin "AF20"
		)
		(pin "AF24"
		)
		(pin "B22"
		)
		(pin "B14"
		)
		(pin "D4"
		)
		(pin "AA18"
		)
		(pin "C22"
		)
		(pin "V24"
		)
		(pin "A12"
		)
		(pin "C7"
		)
		(pin "M7"
		)
		(pin "AB5"
		)
		(pin "W18"
		)
		(pin "T18"
		)
		(pin "T21"
		)
		(pin "F13"
		)
		(pin "D3"
		)
		(pin "F1"
		)
		(pin "L21"
		)
		(pin "L26"
		)
		(pin "AA11"
		)
		(pin "M20"
		)
		(pin "AC4"
		)
		(pin "AE5"
		)
		(pin "D19"
		)
		(pin "E10"
		)
		(pin "AA9"
		)
		(pin "Y22"
		)
		(pin "V3"
		)
		(pin "V4"
		)
		(pin "AD2"
		)
		(pin "AC10"
		)
		(pin "C25"
		)
		(pin "G4"
		)
		(pin "A6"
		)
		(pin "E6"
		)
		(pin "E7"
		)
		(pin "E1"
		)
		(pin "E19"
		)
		(pin "R4"
		)
		(pin "T10"
		)
		(pin "T11"
		)
		(pin "J10"
		)
		(pin "F17"
		)
		(pin "A24"
		)
		(pin "AC15"
		)
		(pin "C15"
		)
		(pin "A1"
		)
		(pin "J1"
		)
		(pin "J17"
		)
		(pin "AE6"
		)
		(pin "E4"
		)
		(pin "E5"
		)
		(pin "M23"
		)
		(pin "M3"
		)
		(pin "R22"
		)
		(pin "AA5"
		)
		(pin "AC12"
		)
		(pin "Y18"
		)
		(pin "W20"
		)
		(pin "AC21"
		)
		(pin "R23"
		)
		(pin "K10"
		)
		(pin "AC17"
		)
		(pin "AC20"
		)
		(pin "V20"
		)
		(pin "V25"
		)
		(pin "N1"
		)
		(pin "N10"
		)
		(pin "M4"
		)
		(pin "M5"
		)
		(pin "R25"
		)
		(pin "H3"
		)
		(pin "H4"
		)
		(pin "AD13"
		)
		(pin "AD17"
		)
		(pin "N26"
		)
		(pin "R13"
		)
		(pin "N6"
		)
		(pin "N7"
		)
		(pin "U4"
		)
		(pin "R5"
		)
		(pin "K3"
		)
		(pin "K4"
		)
		(pin "AF3"
		)
		(pin "J5"
		)
		(pin "P2"
		)
		(pin "N22"
		)
		(pin "T16"
		)
		(pin "T17"
		)
		(pin "C3"
		)
		(pin "AF4"
		)
		(pin "T13"
		)
		(pin "AA12"
		)
		(pin "AB26"
		)
		(pin "AF21"
		)
		(pin "N25"
		)
		(pin "N3"
		)
		(pin "N21"
		)
		(pin "J12"
		)
		(pin "A8"
		)
		(pin "W12"
		)
		(pin "H14"
		)
		(pin "U21"
		)
		(pin "W9"
		)
		(pin "T14"
		)
		(pin "AE23"
		)
		(pin "K19"
		)
		(pin "K24"
		)
		(pin "Y25"
		)
		(pin "G12"
		)
		(pin "N2"
		)
		(pin "N20"
		)
		(pin "T25"
		)
		(pin "AC8"
		)
		(pin "E16"
		)
		(pin "AC19"
		)
		(pin "C14"
		)
		(pin "F4"
		)
		(pin "F5"
		)
		(pin "U19"
		)
		(pin "AE12"
		)
		(pin "P14"
		)
		(pin "AF8"
		)
		(pin "AF9"
		)
		(pin "V26"
		)
		(pin "W19"
		)
		(pin "L4"
		)
		(pin "G24"
		)
		(pin "R15"
		)
		(pin "R16"
		)
		(pin "U5"
		)
		(pin "AC16"
		)
		(pin "AF25"
		)
		(pin "T7"
		)
		(pin "F24"
		)
		(pin "D16"
		)
		(pin "AA19"
		)
		(pin "D5"
		)
		(pin "L22"
		)
		(pin "B17"
		)
		(pin "H15"
		)
		(pin "AE21"
		)
		(pin "AE7"
		)
		(pin "K5"
		)
		(pin "K6"
		)
		(pin "T1"
		)
		(pin "AE22"
		)
		(pin "E22"
		)
		(pin "AF10"
		)
		(pin "AB6"
		)
		(pin "AD26"
		)
		(pin "AC13"
		)
		(pin "E18"
		)
		(pin "M15"
		)
		(pin "M16"
		)
		(pin "G15"
		)
		(pin "N8"
		)
		(pin "N9"
		)
		(pin "W26"
		)
		(pin "F20"
		)
		(pin "AD23"
		)
		(pin "AA8"
		)
		(pin "D20"
		)
		(pin "AF11"
		)
		(pin "E8"
		)
		(pin "F11"
		)
		(pin "AC5"
		)
		(pin "AA22"
		)
		(pin "E20"
		)
		(pin "W14"
		)
		(pin "M19"
		)
		(pin "H24"
		)
		(pin "K7"
		)
		(pin "K8"
		)
		(pin "C4"
		)
		(pin "H25"
		)
		(pin "W21"
		)
		(pin "P13"
		)
		(pin "L20"
		)
		(pin "AB21"
		)
		(pin "C2"
		)
		(pin "H22"
		)
		(pin "Y17"
		)
		(pin "AE11"
		)
		(pin "H2"
		)
		(pin "F23"
		)
		(pin "E11"
		)
		(pin "AB24"
		)
		(pin "AA4"
		)
		(pin "T6"
		)
		(pin "AD20"
		)
		(pin "A10"
		)
		(pin "C9"
		)
		(pin "W15"
		)
		(pin "E21"
		)
		(pin "AB22"
		)
		(pin "W16"
		)
		(pin "AC25"
		)
		(pin "T22"
		)
		(pin "K1"
		)
		(pin "AD14"
		)
		(pin "T2"
		)
		(pin "J19"
		)
		(pin "D9"
		)
		(pin "AE17"
		)
		(pin "AB1"
		)
		(pin "T24"
		)
		(pin "F9"
		)
		(pin "M8"
		)
		(pin "M9"
		)
		(pin "Y23"
		)
		(pin "AC7"
		)
		(pin "M13"
		)
		(pin "M14"
		)
		(pin "G25"
		)
		(pin "A9"
		)
		(pin "AB19"
		)
		(pin "A7"
		)
		(pin "N15"
		)
		(pin "N16"
		)
		(pin "Y13"
		)
		(pin "AF5"
		)
		(pin "R14"
		)
		(pin "AE20"
		)
		(pin "AB11"
		)
		(pin "W25"
		)
		(pin "T19"
		)
		(pin "H21"
		)
		(pin "K2"
		)
		(pin "T23"
		)
		(pin "AC6"
		)
		(pin "B15"
		)
		(pin "E9"
		)
		(pin "AC3"
		)
		(pin "F10"
		)
		(pin "A3"
		)
		(pin "F15"
		)
		(pin "U20"
		)
		(pin "G10"
		)
		(pin "N23"
		)
		(pin "AB15"
		)
		(pin "AA21"
		)
		(pin "P10"
		)
		(pin "P11"
		)
		(pin "J11"
		)
		(pin "Y10"
		)
		(pin "F19"
		)
		(pin "A22"
		)
		(pin "AE16"
		)
		(pin "F22"
		)
		(pin "G11"
		)
		(pin "K25"
		)
		(pin "B10"
		)
		(pin "AA20"
		)
		(pin "N24"
		)
		(pin "AA25"
		)
		(pin "E12"
		)
		(pin "D11"
		)
		(pin "E14"
		)
		(pin "AC1"
		)
		(pin "J4"
		)
		(pin "H11"
		)
		(pin "H9"
		)
		(pin "M22"
		)
		(pin "H10"
		)
		(pin "E13"
		)
		(pin "AD21"
		)
		(pin "D10"
		)
		(pin "B11"
		)
		(pin "G26"
		)
		(pin "L25"
		)
		(pin "AB9"
		)
		(pin "A2"
		)
		(pin "M21"
		)
		(pin "C11"
		)
		(pin "R21"
		)
		(pin "D14"
		)
		(pin "F12"
		)
		(pin "B9"
		)
		(pin "J9"
		)
		(pin "L19"
		)
		(pin "B16"
		)
		(pin "K22"
		)
		(pin "K26"
		)
		(pin "N11"
		)
		(pin "N12"
		)
		(pin "A16"
		)
		(pin "AB12"
		)
		(pin "L7"
		)
		(pin "L8"
		)
		(pin "AC11"
		)
		(pin "J18"
		)
		(pin "K16"
		)
		(pin "K17"
		)
		(pin "M24"
		)
		(pin "M17"
		)
		(pin "M18"
		)
		(pin "J14"
		)
		(pin "R8"
		)
		(pin "R9"
		)
		(pin "A26"
		)
		(pin "H23"
		)
		(pin "AF16"
		)
		(pin "F26"
		)
		(pin "F3"
		)
		(pin "AC18"
		)
		(pin "W10"
		)
		(pin "G9"
		)
		(pin "K14"
		)
		(pin "K15"
		)
		(pin "N17"
		)
		(pin "N18"
		)
		(pin "AC9"
		)
		(pin "J13"
		)
		(pin "AE24"
		)
		(pin "AA23"
		)
		(pin "E2"
		)
		(pin "E3"
		)
		(pin "AE2"
		)
		(pin "AF26"
		)
		(pin "A21"
		)
		(pin "L9"
		)
		(pin "M10"
		)
		(pin "F16"
		)
		(pin "F21"
		)
		(pin "R26"
		)
		(pin "T12"
		)
		(pin "T15"
		)
		(pin "AB8"
		)
		(pin "A18"
		)
		(pin "A4"
		)
		(pin "AD11"
		)
		(instances
			(project "data-center-rdimm-ddr5-tester"
				(path ""
					(reference "U34")
					(unit 8)
				)
			)
		)
	)
	(symbol
		(lib_id "antmicroFPGAChips:XCAU25P-2FFVB676I")
		(at 93.98 72.39 0)
		(unit 7)
		(exclude_from_sim no)
		(in_bom yes)
		(on_board yes)
		(dnp no)
		(property "Reference" "U34"
			(at 99.695 66.04 0)
			(effects
				(font
					(size 1.27 1.27)
					(thickness 0.15)
				)
				(justify left)
			)
		)
		(property "Value" "XCAU25P-2FFVB676I"
			(at 157.48 77.47 0)
			(effects
				(font
					(size 1.27 1.27)
					(thickness 0.15)
				)
				(justify left bottom)
				(hide yes)
			)
		)
		(property "Footprint" "antmicro-footprints:BGA-676_27x27mm_Layout26x26_P1x1mm_FFVB676"
			(at 157.48 80.01 0)
			(effects
				(font
					(size 1.27 1.27)
					(thickness 0.15)
				)
				(justify left bottom)
				(hide yes)
			)
		)
		(property "Datasheet" "https://docs.xilinx.com/viewer/book-attachment/2PXOpPtpaABIt0fkzeBLnw/hvbsEUaOT0OxFhln7VEVyA"
			(at 157.48 82.55 0)
			(effects
				(font
					(size 1.27 1.27)
					(thickness 0.15)
				)
				(justify left bottom)
				(hide yes)
			)
		)
		(property "Description" ""
			(at 93.98 72.39 0)
			(effects
				(font
					(size 1.27 1.27)
				)
				(hide yes)
			)
		)
		(property "MPN" "XCAU25P-2FFVB676I"
			(at 99.695 68.58 0)
			(effects
				(font
					(size 1.27 1.27)
					(thickness 0.15)
				)
				(justify left)
			)
		)
		(property "Manufacturer" "AMD-Xilinx"
			(at 157.48 85.09 0)
			(effects
				(font
					(size 1.27 1.27)
					(thickness 0.15)
				)
				(justify left bottom)
				(hide yes)
			)
		)
		(property "Author" "Antmicro"
			(at 157.48 87.63 0)
			(effects
				(font
					(size 1.27 1.27)
					(thickness 0.15)
				)
				(justify left bottom)
				(hide yes)
			)
		)
		(property "License" "Apache-2.0"
			(at 157.48 90.17 0)
			(effects
				(font
					(size 1.27 1.27)
					(thickness 0.15)
				)
				(justify left bottom)
				(hide yes)
			)
		)
		(pin "AC23"
		)
		(pin "P20"
		)
		(pin "N19"
		)
		(pin "AA24"
		)
		(pin "J16"
		)
		(pin "J21"
		)
		(pin "AE10"
		)
		(pin "F6"
		)
		(pin "F7"
		)
		(pin "AF17"
		)
		(pin "AA15"
		)
		(pin "J25"
		)
		(pin "Y21"
		)
		(pin "AA7"
		)
		(pin "E26"
		)
		(pin "AD16"
		)
		(pin "V1"
		)
		(pin "AB14"
		)
		(pin "Y1"
		)
		(pin "E24"
		)
		(pin "AA14"
		)
		(pin "J20"
		)
		(pin "U25"
		)
		(pin "AE18"
		)
		(pin "U22"
		)
		(pin "P4"
		)
		(pin "P5"
		)
		(pin "R1"
		)
		(pin "R10"
		)
		(pin "P8"
		)
		(pin "P9"
		)
		(pin "R11"
		)
		(pin "R12"
		)
		(pin "AD3"
		)
		(pin "AD9"
		)
		(pin "AD4"
		)
		(pin "P18"
		)
		(pin "P3"
		)
		(pin "G14"
		)
		(pin "AE26"
		)
		(pin "B12"
		)
		(pin "AC2"
		)
		(pin "W7"
		)
		(pin "W8"
		)
		(pin "W11"
		)
		(pin "W17"
		)
		(pin "W2"
		)
		(pin "W22"
		)
		(pin "W3"
		)
		(pin "W6"
		)
		(pin "P6"
		)
		(pin "U26"
		)
		(pin "P19"
		)
		(pin "U1"
		)
		(pin "U10"
		)
		(pin "J15"
		)
		(pin "AB25"
		)
		(pin "L23"
		)
		(pin "P24"
		)
		(pin "G16"
		)
		(pin "C10"
		)
		(pin "F14"
		)
		(pin "U24"
		)
		(pin "Y24"
		)
		(pin "Y11"
		)
		(pin "J26"
		)
		(pin "AB4"
		)
		(pin "AD18"
		)
		(pin "J24"
		)
		(pin "AF2"
		)
		(pin "B26"
		)
		(pin "U6"
		)
		(pin "U7"
		)
		(pin "M11"
		)
		(pin "M12"
		)
		(pin "T20"
		)
		(pin "V23"
		)
		(pin "AD10"
		)
		(pin "D1"
		)
		(pin "AF1"
		)
		(pin "C8"
		)
		(pin "U13"
		)
		(pin "U14"
		)
		(pin "AD19"
		)
		(pin "Y4"
		)
		(pin "Y5"
		)
		(pin "E23"
		)
		(pin "C6"
		)
		(pin "AE14"
		)
		(pin "D22"
		)
		(pin "C20"
		)
		(pin "AB17"
		)
		(pin "AD24"
		)
		(pin "L1"
		)
		(pin "L10"
		)
		(pin "AE3"
		)
		(pin "G21"
		)
		(pin "AA17"
		)
		(pin "D6"
		)
		(pin "M25"
		)
		(pin "R17"
		)
		(pin "R18"
		)
		(pin "AE15"
		)
		(pin "H7"
		)
		(pin "H8"
		)
		(pin "R6"
		)
		(pin "R7"
		)
		(pin "AB20"
		)
		(pin "C5"
		)
		(pin "Y14"
		)
		(pin "AE13"
		)
		(pin "C13"
		)
		(pin "W4"
		)
		(pin "P22"
		)
		(pin "AF6"
		)
		(pin "B8"
		)
		(pin "AF18"
		)
		(pin "G22"
		)
		(pin "J2"
		)
		(pin "J3"
		)
		(pin "L3"
		)
		(pin "L6"
		)
		(pin "P12"
		)
		(pin "P15"
		)
		(pin "Y12"
		)
		(pin "K18"
		)
		(pin "V10"
		)
		(pin "V11"
		)
		(pin "D7"
		)
		(pin "D8"
		)
		(pin "P23"
		)
		(pin "AA3"
		)
		(pin "AB18"
		)
		(pin "H18"
		)
		(pin "B6"
		)
		(pin "R24"
		)
		(pin "R3"
		)
		(pin "P16"
		)
		(pin "P17"
		)
		(pin "AF23"
		)
		(pin "AC14"
		)
		(pin "M6"
		)
		(pin "B18"
		)
		(pin "M1"
		)
		(pin "B5"
		)
		(pin "D2"
		)
		(pin "G20"
		)
		(pin "M2"
		)
		(pin "B4"
		)
		(pin "AA16"
		)
		(pin "V9"
		)
		(pin "W1"
		)
		(pin "N5"
		)
		(pin "AA26"
		)
		(pin "B3"
		)
		(pin "D12"
		)
		(pin "N4"
		)
		(pin "AA2"
		)
		(pin "B23"
		)
		(pin "C12"
		)
		(pin "L5"
		)
		(pin "AA6"
		)
		(pin "B1"
		)
		(pin "H1"
		)
		(pin "A14"
		)
		(pin "A13"
		)
		(pin "AB2"
		)
		(pin "AE4"
		)
		(pin "Y16"
		)
		(pin "B24"
		)
		(pin "H16"
		)
		(pin "W24"
		)
		(pin "D18"
		)
		(pin "B20"
		)
		(pin "D21"
		)
		(pin "B19"
		)
		(pin "B25"
		)
		(pin "C24"
		)
		(pin "A15"
		)
		(pin "M26"
		)
		(pin "A23"
		)
		(pin "C17"
		)
		(pin "K21"
		)
		(pin "W23"
		)
		(pin "L24"
		)
		(pin "R20"
		)
		(pin "C21"
		)
		(pin "D24"
		)
		(pin "E15"
		)
		(pin "AD12"
		)
		(pin "D23"
		)
		(pin "D25"
		)
		(pin "C26"
		)
		(pin "B21"
		)
		(pin "Y26"
		)
		(pin "AE25"
		)
		(pin "C19"
		)
		(pin "C23"
		)
		(pin "P21"
		)
		(pin "A20"
		)
		(pin "L18"
		)
		(pin "A25"
		)
		(pin "K23"
		)
		(pin "V18"
		)
		(pin "C16"
		)
		(pin "V21"
		)
		(pin "E17"
		)
		(pin "A17"
		)
		(pin "P25"
		)
		(pin "AD25"
		)
		(pin "G18"
		)
		(pin "AB3"
		)
		(pin "J6"
		)
		(pin "J7"
		)
		(pin "K12"
		)
		(pin "K13"
		)
		(pin "AB16"
		)
		(pin "C1"
		)
		(pin "AF15"
		)
		(pin "J8"
		)
		(pin "K11"
		)
		(pin "AD1"
		)
		(pin "F25"
		)
		(pin "AE1"
		)
		(pin "V2"
		)
		(pin "U2"
		)
		(pin "U3"
		)
		(pin "F2"
		)
		(pin "V6"
		)
		(pin "P1"
		)
		(pin "L13"
		)
		(pin "L14"
		)
		(pin "AD5"
		)
		(pin "AE8"
		)
		(pin "AB10"
		)
		(pin "U15"
		)
		(pin "U16"
		)
		(pin "U17"
		)
		(pin "U18"
		)
		(pin "D26"
		)
		(pin "G5"
		)
		(pin "E25"
		)
		(pin "AD22"
		)
		(pin "A19"
		)
		(pin "P7"
		)
		(pin "Y2"
		)
		(pin "J22"
		)
		(pin "Y19"
		)
		(pin "Y3"
		)
		(pin "AB7"
		)
		(pin "AF22"
		)
		(pin "B2"
		)
		(pin "AA10"
		)
		(pin "V7"
		)
		(pin "V22"
		)
		(pin "J23"
		)
		(pin "AF12"
		)
		(pin "V16"
		)
		(pin "V17"
		)
		(pin "Y7"
		)
		(pin "D15"
		)
		(pin "H12"
		)
		(pin "AF7"
		)
		(pin "U23"
		)
		(pin "V19"
		)
		(pin "AF14"
		)
		(pin "AF13"
		)
		(pin "G8"
		)
		(pin "H20"
		)
		(pin "U11"
		)
		(pin "U12"
		)
		(pin "A5"
		)
		(pin "G6"
		)
		(pin "G7"
		)
		(pin "L15"
		)
		(pin "L16"
		)
		(pin "T8"
		)
		(pin "T9"
		)
		(pin "G19"
		)
		(pin "G17"
		)
		(pin "T4"
		)
		(pin "T5"
		)
		(pin "B13"
		)
		(pin "G23"
		)
		(pin "G3"
		)
		(pin "T26"
		)
		(pin "T3"
		)
		(pin "G13"
		)
		(pin "G2"
		)
		(pin "D17"
		)
		(pin "AD15"
		)
		(pin "Y8"
		)
		(pin "Y9"
		)
		(pin "AC24"
		)
		(pin "AD8"
		)
		(pin "F8"
		)
		(pin "G1"
		)
		(pin "AD6"
		)
		(pin "F18"
		)
		(pin "H17"
		)
		(pin "AA13"
		)
		(pin "K20"
		)
		(pin "AD7"
		)
		(pin "AA1"
		)
		(pin "AF19"
		)
		(pin "Y15"
		)
		(pin "AB13"
		)
		(pin "N13"
		)
		(pin "N14"
		)
		(pin "V14"
		)
		(pin "V15"
		)
		(pin "U8"
		)
		(pin "U9"
		)
		(pin "W13"
		)
		(pin "V5"
		)
		(pin "V8"
		)
		(pin "W5"
		)
		(pin "P26"
		)
		(pin "Y20"
		)
		(pin "L17"
		)
		(pin "L2"
		)
		(pin "H26"
		)
		(pin "Y6"
		)
		(pin "AC22"
		)
		(pin "D13"
		)
		(pin "V12"
		)
		(pin "V13"
		)
		(pin "AE9"
		)
		(pin "B7"
		)
		(pin "A11"
		)
		(pin "K9"
		)
		(pin "L11"
		)
		(pin "L12"
		)
		(pin "H5"
		)
		(pin "H6"
		)
		(pin "AE19"
		)
		(pin "C18"
		)
		(pin "H13"
		)
		(pin "AB23"
		)
		(pin "AC26"
		)
		(pin "R19"
		)
		(pin "R2"
		)
		(pin "H19"
		)
		(pin "AF20"
		)
		(pin "AF24"
		)
		(pin "B22"
		)
		(pin "B14"
		)
		(pin "D4"
		)
		(pin "AA18"
		)
		(pin "C22"
		)
		(pin "V24"
		)
		(pin "A12"
		)
		(pin "C7"
		)
		(pin "M7"
		)
		(pin "AB5"
		)
		(pin "W18"
		)
		(pin "T18"
		)
		(pin "T21"
		)
		(pin "F13"
		)
		(pin "D3"
		)
		(pin "F1"
		)
		(pin "L21"
		)
		(pin "L26"
		)
		(pin "AA11"
		)
		(pin "M20"
		)
		(pin "AC4"
		)
		(pin "AE5"
		)
		(pin "D19"
		)
		(pin "E10"
		)
		(pin "AA9"
		)
		(pin "Y22"
		)
		(pin "V3"
		)
		(pin "V4"
		)
		(pin "AD2"
		)
		(pin "AC10"
		)
		(pin "C25"
		)
		(pin "G4"
		)
		(pin "A6"
		)
		(pin "E6"
		)
		(pin "E7"
		)
		(pin "E1"
		)
		(pin "E19"
		)
		(pin "R4"
		)
		(pin "T10"
		)
		(pin "T11"
		)
		(pin "J10"
		)
		(pin "F17"
		)
		(pin "A24"
		)
		(pin "AC15"
		)
		(pin "C15"
		)
		(pin "A1"
		)
		(pin "J1"
		)
		(pin "J17"
		)
		(pin "AE6"
		)
		(pin "E4"
		)
		(pin "E5"
		)
		(pin "M23"
		)
		(pin "M3"
		)
		(pin "R22"
		)
		(pin "AA5"
		)
		(pin "AC12"
		)
		(pin "Y18"
		)
		(pin "W20"
		)
		(pin "AC21"
		)
		(pin "R23"
		)
		(pin "K10"
		)
		(pin "AC17"
		)
		(pin "AC20"
		)
		(pin "V20"
		)
		(pin "V25"
		)
		(pin "N1"
		)
		(pin "N10"
		)
		(pin "M4"
		)
		(pin "M5"
		)
		(pin "R25"
		)
		(pin "H3"
		)
		(pin "H4"
		)
		(pin "AD13"
		)
		(pin "AD17"
		)
		(pin "N26"
		)
		(pin "R13"
		)
		(pin "N6"
		)
		(pin "N7"
		)
		(pin "U4"
		)
		(pin "R5"
		)
		(pin "K3"
		)
		(pin "K4"
		)
		(pin "AF3"
		)
		(pin "J5"
		)
		(pin "P2"
		)
		(pin "N22"
		)
		(pin "T16"
		)
		(pin "T17"
		)
		(pin "C3"
		)
		(pin "AF4"
		)
		(pin "T13"
		)
		(pin "AA12"
		)
		(pin "AB26"
		)
		(pin "AF21"
		)
		(pin "N25"
		)
		(pin "N3"
		)
		(pin "N21"
		)
		(pin "J12"
		)
		(pin "A8"
		)
		(pin "W12"
		)
		(pin "H14"
		)
		(pin "U21"
		)
		(pin "W9"
		)
		(pin "T14"
		)
		(pin "AE23"
		)
		(pin "K19"
		)
		(pin "K24"
		)
		(pin "Y25"
		)
		(pin "G12"
		)
		(pin "N2"
		)
		(pin "N20"
		)
		(pin "T25"
		)
		(pin "AC8"
		)
		(pin "E16"
		)
		(pin "AC19"
		)
		(pin "C14"
		)
		(pin "F4"
		)
		(pin "F5"
		)
		(pin "U19"
		)
		(pin "AE12"
		)
		(pin "P14"
		)
		(pin "AF8"
		)
		(pin "AF9"
		)
		(pin "V26"
		)
		(pin "W19"
		)
		(pin "L4"
		)
		(pin "G24"
		)
		(pin "R15"
		)
		(pin "R16"
		)
		(pin "U5"
		)
		(pin "AC16"
		)
		(pin "AF25"
		)
		(pin "T7"
		)
		(pin "F24"
		)
		(pin "D16"
		)
		(pin "AA19"
		)
		(pin "D5"
		)
		(pin "L22"
		)
		(pin "B17"
		)
		(pin "H15"
		)
		(pin "AE21"
		)
		(pin "AE7"
		)
		(pin "K5"
		)
		(pin "K6"
		)
		(pin "T1"
		)
		(pin "AE22"
		)
		(pin "E22"
		)
		(pin "AF10"
		)
		(pin "AB6"
		)
		(pin "AD26"
		)
		(pin "AC13"
		)
		(pin "E18"
		)
		(pin "M15"
		)
		(pin "M16"
		)
		(pin "G15"
		)
		(pin "N8"
		)
		(pin "N9"
		)
		(pin "W26"
		)
		(pin "F20"
		)
		(pin "AD23"
		)
		(pin "AA8"
		)
		(pin "D20"
		)
		(pin "AF11"
		)
		(pin "E8"
		)
		(pin "F11"
		)
		(pin "AC5"
		)
		(pin "AA22"
		)
		(pin "E20"
		)
		(pin "W14"
		)
		(pin "M19"
		)
		(pin "H24"
		)
		(pin "K7"
		)
		(pin "K8"
		)
		(pin "C4"
		)
		(pin "H25"
		)
		(pin "W21"
		)
		(pin "P13"
		)
		(pin "L20"
		)
		(pin "AB21"
		)
		(pin "C2"
		)
		(pin "H22"
		)
		(pin "Y17"
		)
		(pin "AE11"
		)
		(pin "H2"
		)
		(pin "F23"
		)
		(pin "E11"
		)
		(pin "AB24"
		)
		(pin "AA4"
		)
		(pin "T6"
		)
		(pin "AD20"
		)
		(pin "A10"
		)
		(pin "C9"
		)
		(pin "W15"
		)
		(pin "E21"
		)
		(pin "AB22"
		)
		(pin "W16"
		)
		(pin "AC25"
		)
		(pin "T22"
		)
		(pin "K1"
		)
		(pin "AD14"
		)
		(pin "T2"
		)
		(pin "J19"
		)
		(pin "D9"
		)
		(pin "AE17"
		)
		(pin "AB1"
		)
		(pin "T24"
		)
		(pin "F9"
		)
		(pin "M8"
		)
		(pin "M9"
		)
		(pin "Y23"
		)
		(pin "AC7"
		)
		(pin "M13"
		)
		(pin "M14"
		)
		(pin "G25"
		)
		(pin "A9"
		)
		(pin "AB19"
		)
		(pin "A7"
		)
		(pin "N15"
		)
		(pin "N16"
		)
		(pin "Y13"
		)
		(pin "AF5"
		)
		(pin "R14"
		)
		(pin "AE20"
		)
		(pin "AB11"
		)
		(pin "W25"
		)
		(pin "T19"
		)
		(pin "H21"
		)
		(pin "K2"
		)
		(pin "T23"
		)
		(pin "AC6"
		)
		(pin "B15"
		)
		(pin "E9"
		)
		(pin "AC3"
		)
		(pin "F10"
		)
		(pin "A3"
		)
		(pin "F15"
		)
		(pin "U20"
		)
		(pin "G10"
		)
		(pin "N23"
		)
		(pin "AB15"
		)
		(pin "AA21"
		)
		(pin "P10"
		)
		(pin "P11"
		)
		(pin "J11"
		)
		(pin "Y10"
		)
		(pin "F19"
		)
		(pin "A22"
		)
		(pin "AE16"
		)
		(pin "F22"
		)
		(pin "G11"
		)
		(pin "K25"
		)
		(pin "B10"
		)
		(pin "AA20"
		)
		(pin "N24"
		)
		(pin "AA25"
		)
		(pin "E12"
		)
		(pin "D11"
		)
		(pin "E14"
		)
		(pin "AC1"
		)
		(pin "J4"
		)
		(pin "H11"
		)
		(pin "H9"
		)
		(pin "M22"
		)
		(pin "H10"
		)
		(pin "E13"
		)
		(pin "AD21"
		)
		(pin "D10"
		)
		(pin "B11"
		)
		(pin "G26"
		)
		(pin "L25"
		)
		(pin "AB9"
		)
		(pin "A2"
		)
		(pin "M21"
		)
		(pin "C11"
		)
		(pin "R21"
		)
		(pin "D14"
		)
		(pin "F12"
		)
		(pin "B9"
		)
		(pin "J9"
		)
		(pin "L19"
		)
		(pin "B16"
		)
		(pin "K22"
		)
		(pin "K26"
		)
		(pin "N11"
		)
		(pin "N12"
		)
		(pin "A16"
		)
		(pin "AB12"
		)
		(pin "L7"
		)
		(pin "L8"
		)
		(pin "AC11"
		)
		(pin "J18"
		)
		(pin "K16"
		)
		(pin "K17"
		)
		(pin "M24"
		)
		(pin "M17"
		)
		(pin "M18"
		)
		(pin "J14"
		)
		(pin "R8"
		)
		(pin "R9"
		)
		(pin "A26"
		)
		(pin "H23"
		)
		(pin "AF16"
		)
		(pin "F26"
		)
		(pin "F3"
		)
		(pin "AC18"
		)
		(pin "W10"
		)
		(pin "G9"
		)
		(pin "K14"
		)
		(pin "K15"
		)
		(pin "N17"
		)
		(pin "N18"
		)
		(pin "AC9"
		)
		(pin "J13"
		)
		(pin "AE24"
		)
		(pin "AA23"
		)
		(pin "E2"
		)
		(pin "E3"
		)
		(pin "AE2"
		)
		(pin "AF26"
		)
		(pin "A21"
		)
		(pin "L9"
		)
		(pin "M10"
		)
		(pin "F16"
		)
		(pin "F21"
		)
		(pin "R26"
		)
		(pin "T12"
		)
		(pin "T15"
		)
		(pin "AB8"
		)
		(pin "A18"
		)
		(pin "A4"
		)
		(pin "AD11"
		)
		(instances
			(project "data-center-rdimm-ddr5-tester"
				(path ""
					(reference "U34")
					(unit 7)
				)
			)
		)
	)
	(symbol
		(lib_id "antmicropower:+3V3")
		(at 227.33 218.44 0)
		(unit 1)
		(exclude_from_sim no)
		(in_bom yes)
		(on_board yes)
		(dnp no)
		(fields_autoplaced yes)
		(property "Reference" "#PWR0426"
			(at 227.33 222.25 0)
			(effects
				(font
					(size 1.27 1.27)
				)
				(hide yes)
			)
		)
		(property "Value" "+3V3"
			(at 224.155 215.9 0)
			(effects
				(font
					(size 1.27 1.27)
					(thickness 0.15)
				)
				(justify left bottom)
			)
		)
		(property "Footprint" ""
			(at 242.57 226.06 0)
			(effects
				(font
					(size 1.27 1.27)
					(thickness 0.15)
				)
				(justify left bottom)
				(hide yes)
			)
		)
		(property "Datasheet" ""
			(at 242.57 228.6 0)
			(effects
				(font
					(size 1.27 1.27)
					(thickness 0.15)
				)
				(justify left bottom)
				(hide yes)
			)
		)
		(property "Description" ""
			(at 227.33 218.44 0)
			(effects
				(font
					(size 1.27 1.27)
				)
				(hide yes)
			)
		)
		(property "Author" "Antmicro"
			(at 242.57 220.98 0)
			(effects
				(font
					(size 1.27 1.27)
					(thickness 0.15)
				)
				(justify left bottom)
				(hide yes)
			)
		)
		(property "License" "Apache-2.0"
			(at 242.57 223.52 0)
			(effects
				(font
					(size 1.27 1.27)
					(thickness 0.15)
				)
				(justify left bottom)
				(hide yes)
			)
		)
		(pin "1"
		)
		(instances
			(project "data-center-rdimm-ddr5-tester"
				(path ""
					(reference "#PWR0426")
					(unit 1)
				)
			)
		)
	)
	(symbol
		(lib_name "XCAU25P-2FFVB676I_2")
		(lib_id "antmicroFPGAChips:XCAU25P-2FFVB676I")
		(at 318.77 72.39 0)
		(unit 6)
		(exclude_from_sim no)
		(in_bom yes)
		(on_board yes)
		(dnp no)
		(property "Reference" "U34"
			(at 324.485 66.04 0)
			(effects
				(font
					(size 1.27 1.27)
					(thickness 0.15)
				)
				(justify left)
			)
		)
		(property "Value" "XCAU25P-2FFVB676I"
			(at 382.27 77.47 0)
			(effects
				(font
					(size 1.27 1.27)
					(thickness 0.15)
				)
				(justify left bottom)
				(hide yes)
			)
		)
		(property "Footprint" "antmicro-footprints:BGA-676_27x27mm_Layout26x26_P1x1mm_FFVB676"
			(at 382.27 80.01 0)
			(effects
				(font
					(size 1.27 1.27)
					(thickness 0.15)
				)
				(justify left bottom)
				(hide yes)
			)
		)
		(property "Datasheet" "https://docs.xilinx.com/viewer/book-attachment/2PXOpPtpaABIt0fkzeBLnw/hvbsEUaOT0OxFhln7VEVyA"
			(at 382.27 82.55 0)
			(effects
				(font
					(size 1.27 1.27)
					(thickness 0.15)
				)
				(justify left bottom)
				(hide yes)
			)
		)
		(property "Description" ""
			(at 318.77 72.39 0)
			(effects
				(font
					(size 1.27 1.27)
				)
				(hide yes)
			)
		)
		(property "MPN" "XCAU25P-2FFVB676I"
			(at 324.485 68.58 0)
			(effects
				(font
					(size 1.27 1.27)
					(thickness 0.15)
				)
				(justify left)
			)
		)
		(property "Manufacturer" "AMD-Xilinx"
			(at 382.27 85.09 0)
			(effects
				(font
					(size 1.27 1.27)
					(thickness 0.15)
				)
				(justify left bottom)
				(hide yes)
			)
		)
		(property "Author" "Antmicro"
			(at 382.27 87.63 0)
			(effects
				(font
					(size 1.27 1.27)
					(thickness 0.15)
				)
				(justify left bottom)
				(hide yes)
			)
		)
		(property "License" "Apache-2.0"
			(at 382.27 90.17 0)
			(effects
				(font
					(size 1.27 1.27)
					(thickness 0.15)
				)
				(justify left bottom)
				(hide yes)
			)
		)
		(pin "AC23"
		)
		(pin "P20"
		)
		(pin "N19"
		)
		(pin "AA24"
		)
		(pin "J16"
		)
		(pin "J21"
		)
		(pin "AE10"
		)
		(pin "F6"
		)
		(pin "F7"
		)
		(pin "AF17"
		)
		(pin "AA15"
		)
		(pin "J25"
		)
		(pin "Y21"
		)
		(pin "AA7"
		)
		(pin "E26"
		)
		(pin "AD16"
		)
		(pin "V1"
		)
		(pin "AB14"
		)
		(pin "Y1"
		)
		(pin "E24"
		)
		(pin "AA14"
		)
		(pin "J20"
		)
		(pin "U25"
		)
		(pin "AE18"
		)
		(pin "U22"
		)
		(pin "P4"
		)
		(pin "P5"
		)
		(pin "R1"
		)
		(pin "R10"
		)
		(pin "P8"
		)
		(pin "P9"
		)
		(pin "R11"
		)
		(pin "R12"
		)
		(pin "AD3"
		)
		(pin "AD9"
		)
		(pin "AD4"
		)
		(pin "P18"
		)
		(pin "P3"
		)
		(pin "G14"
		)
		(pin "AE26"
		)
		(pin "B12"
		)
		(pin "AC2"
		)
		(pin "W7"
		)
		(pin "W8"
		)
		(pin "W11"
		)
		(pin "W17"
		)
		(pin "W2"
		)
		(pin "W22"
		)
		(pin "W3"
		)
		(pin "W6"
		)
		(pin "P6"
		)
		(pin "U26"
		)
		(pin "P19"
		)
		(pin "U1"
		)
		(pin "U10"
		)
		(pin "J15"
		)
		(pin "AB25"
		)
		(pin "L23"
		)
		(pin "P24"
		)
		(pin "G16"
		)
		(pin "C10"
		)
		(pin "F14"
		)
		(pin "U24"
		)
		(pin "Y24"
		)
		(pin "Y11"
		)
		(pin "J26"
		)
		(pin "AB4"
		)
		(pin "AD18"
		)
		(pin "J24"
		)
		(pin "AF2"
		)
		(pin "B26"
		)
		(pin "U6"
		)
		(pin "U7"
		)
		(pin "M11"
		)
		(pin "M12"
		)
		(pin "T20"
		)
		(pin "V23"
		)
		(pin "AD10"
		)
		(pin "D1"
		)
		(pin "AF1"
		)
		(pin "C8"
		)
		(pin "U13"
		)
		(pin "U14"
		)
		(pin "AD19"
		)
		(pin "Y4"
		)
		(pin "Y5"
		)
		(pin "E23"
		)
		(pin "C6"
		)
		(pin "AE14"
		)
		(pin "D22"
		)
		(pin "C20"
		)
		(pin "AB17"
		)
		(pin "AD24"
		)
		(pin "L1"
		)
		(pin "L10"
		)
		(pin "AE3"
		)
		(pin "G21"
		)
		(pin "AA17"
		)
		(pin "D6"
		)
		(pin "M25"
		)
		(pin "R17"
		)
		(pin "R18"
		)
		(pin "AE15"
		)
		(pin "H7"
		)
		(pin "H8"
		)
		(pin "R6"
		)
		(pin "R7"
		)
		(pin "AB20"
		)
		(pin "C5"
		)
		(pin "Y14"
		)
		(pin "AE13"
		)
		(pin "C13"
		)
		(pin "W4"
		)
		(pin "P22"
		)
		(pin "AF6"
		)
		(pin "B8"
		)
		(pin "AF18"
		)
		(pin "G22"
		)
		(pin "J2"
		)
		(pin "J3"
		)
		(pin "L3"
		)
		(pin "L6"
		)
		(pin "P12"
		)
		(pin "P15"
		)
		(pin "Y12"
		)
		(pin "K18"
		)
		(pin "V10"
		)
		(pin "V11"
		)
		(pin "D7"
		)
		(pin "D8"
		)
		(pin "P23"
		)
		(pin "AA3"
		)
		(pin "AB18"
		)
		(pin "H18"
		)
		(pin "B6"
		)
		(pin "R24"
		)
		(pin "R3"
		)
		(pin "P16"
		)
		(pin "P17"
		)
		(pin "AF23"
		)
		(pin "AC14"
		)
		(pin "M6"
		)
		(pin "B18"
		)
		(pin "M1"
		)
		(pin "B5"
		)
		(pin "D2"
		)
		(pin "G20"
		)
		(pin "M2"
		)
		(pin "B4"
		)
		(pin "AA16"
		)
		(pin "V9"
		)
		(pin "W1"
		)
		(pin "N5"
		)
		(pin "AA26"
		)
		(pin "B3"
		)
		(pin "D12"
		)
		(pin "N4"
		)
		(pin "AA2"
		)
		(pin "B23"
		)
		(pin "C12"
		)
		(pin "L5"
		)
		(pin "AA6"
		)
		(pin "B1"
		)
		(pin "H1"
		)
		(pin "A14"
		)
		(pin "A13"
		)
		(pin "AB2"
		)
		(pin "AE4"
		)
		(pin "Y16"
		)
		(pin "B24"
		)
		(pin "H16"
		)
		(pin "W24"
		)
		(pin "D18"
		)
		(pin "B20"
		)
		(pin "D21"
		)
		(pin "B19"
		)
		(pin "B25"
		)
		(pin "C24"
		)
		(pin "A15"
		)
		(pin "M26"
		)
		(pin "A23"
		)
		(pin "C17"
		)
		(pin "K21"
		)
		(pin "W23"
		)
		(pin "L24"
		)
		(pin "R20"
		)
		(pin "C21"
		)
		(pin "D24"
		)
		(pin "E15"
		)
		(pin "AD12"
		)
		(pin "D23"
		)
		(pin "D25"
		)
		(pin "C26"
		)
		(pin "B21"
		)
		(pin "Y26"
		)
		(pin "AE25"
		)
		(pin "C19"
		)
		(pin "C23"
		)
		(pin "P21"
		)
		(pin "A20"
		)
		(pin "L18"
		)
		(pin "A25"
		)
		(pin "K23"
		)
		(pin "V18"
		)
		(pin "C16"
		)
		(pin "V21"
		)
		(pin "E17"
		)
		(pin "A17"
		)
		(pin "P25"
		)
		(pin "AD25"
		)
		(pin "G18"
		)
		(pin "AB3"
		)
		(pin "J6"
		)
		(pin "J7"
		)
		(pin "K12"
		)
		(pin "K13"
		)
		(pin "AB16"
		)
		(pin "C1"
		)
		(pin "AF15"
		)
		(pin "J8"
		)
		(pin "K11"
		)
		(pin "AD1"
		)
		(pin "F25"
		)
		(pin "AE1"
		)
		(pin "V2"
		)
		(pin "U2"
		)
		(pin "U3"
		)
		(pin "F2"
		)
		(pin "V6"
		)
		(pin "P1"
		)
		(pin "L13"
		)
		(pin "L14"
		)
		(pin "AD5"
		)
		(pin "AE8"
		)
		(pin "AB10"
		)
		(pin "U15"
		)
		(pin "U16"
		)
		(pin "U17"
		)
		(pin "U18"
		)
		(pin "D26"
		)
		(pin "G5"
		)
		(pin "E25"
		)
		(pin "AD22"
		)
		(pin "A19"
		)
		(pin "P7"
		)
		(pin "Y2"
		)
		(pin "J22"
		)
		(pin "Y19"
		)
		(pin "Y3"
		)
		(pin "AB7"
		)
		(pin "AF22"
		)
		(pin "B2"
		)
		(pin "AA10"
		)
		(pin "V7"
		)
		(pin "V22"
		)
		(pin "J23"
		)
		(pin "AF12"
		)
		(pin "V16"
		)
		(pin "V17"
		)
		(pin "Y7"
		)
		(pin "D15"
		)
		(pin "H12"
		)
		(pin "AF7"
		)
		(pin "U23"
		)
		(pin "V19"
		)
		(pin "AF14"
		)
		(pin "AF13"
		)
		(pin "G8"
		)
		(pin "H20"
		)
		(pin "U11"
		)
		(pin "U12"
		)
		(pin "A5"
		)
		(pin "G6"
		)
		(pin "G7"
		)
		(pin "L15"
		)
		(pin "L16"
		)
		(pin "T8"
		)
		(pin "T9"
		)
		(pin "G19"
		)
		(pin "G17"
		)
		(pin "T4"
		)
		(pin "T5"
		)
		(pin "B13"
		)
		(pin "G23"
		)
		(pin "G3"
		)
		(pin "T26"
		)
		(pin "T3"
		)
		(pin "G13"
		)
		(pin "G2"
		)
		(pin "D17"
		)
		(pin "AD15"
		)
		(pin "Y8"
		)
		(pin "Y9"
		)
		(pin "AC24"
		)
		(pin "AD8"
		)
		(pin "F8"
		)
		(pin "G1"
		)
		(pin "AD6"
		)
		(pin "F18"
		)
		(pin "H17"
		)
		(pin "AA13"
		)
		(pin "K20"
		)
		(pin "AD7"
		)
		(pin "AA1"
		)
		(pin "AF19"
		)
		(pin "Y15"
		)
		(pin "AB13"
		)
		(pin "N13"
		)
		(pin "N14"
		)
		(pin "V14"
		)
		(pin "V15"
		)
		(pin "U8"
		)
		(pin "U9"
		)
		(pin "W13"
		)
		(pin "V5"
		)
		(pin "V8"
		)
		(pin "W5"
		)
		(pin "P26"
		)
		(pin "Y20"
		)
		(pin "L17"
		)
		(pin "L2"
		)
		(pin "H26"
		)
		(pin "Y6"
		)
		(pin "AC22"
		)
		(pin "D13"
		)
		(pin "V12"
		)
		(pin "V13"
		)
		(pin "AE9"
		)
		(pin "B7"
		)
		(pin "A11"
		)
		(pin "K9"
		)
		(pin "L11"
		)
		(pin "L12"
		)
		(pin "H5"
		)
		(pin "H6"
		)
		(pin "AE19"
		)
		(pin "C18"
		)
		(pin "H13"
		)
		(pin "AB23"
		)
		(pin "AC26"
		)
		(pin "R19"
		)
		(pin "R2"
		)
		(pin "H19"
		)
		(pin "AF20"
		)
		(pin "AF24"
		)
		(pin "B22"
		)
		(pin "B14"
		)
		(pin "D4"
		)
		(pin "AA18"
		)
		(pin "C22"
		)
		(pin "V24"
		)
		(pin "A12"
		)
		(pin "C7"
		)
		(pin "M7"
		)
		(pin "AB5"
		)
		(pin "W18"
		)
		(pin "T18"
		)
		(pin "T21"
		)
		(pin "F13"
		)
		(pin "D3"
		)
		(pin "F1"
		)
		(pin "L21"
		)
		(pin "L26"
		)
		(pin "AA11"
		)
		(pin "M20"
		)
		(pin "AC4"
		)
		(pin "AE5"
		)
		(pin "D19"
		)
		(pin "E10"
		)
		(pin "AA9"
		)
		(pin "Y22"
		)
		(pin "V3"
		)
		(pin "V4"
		)
		(pin "AD2"
		)
		(pin "AC10"
		)
		(pin "C25"
		)
		(pin "G4"
		)
		(pin "A6"
		)
		(pin "E6"
		)
		(pin "E7"
		)
		(pin "E1"
		)
		(pin "E19"
		)
		(pin "R4"
		)
		(pin "T10"
		)
		(pin "T11"
		)
		(pin "J10"
		)
		(pin "F17"
		)
		(pin "A24"
		)
		(pin "AC15"
		)
		(pin "C15"
		)
		(pin "A1"
		)
		(pin "J1"
		)
		(pin "J17"
		)
		(pin "AE6"
		)
		(pin "E4"
		)
		(pin "E5"
		)
		(pin "M23"
		)
		(pin "M3"
		)
		(pin "R22"
		)
		(pin "AA5"
		)
		(pin "AC12"
		)
		(pin "Y18"
		)
		(pin "W20"
		)
		(pin "AC21"
		)
		(pin "R23"
		)
		(pin "K10"
		)
		(pin "AC17"
		)
		(pin "AC20"
		)
		(pin "V20"
		)
		(pin "V25"
		)
		(pin "N1"
		)
		(pin "N10"
		)
		(pin "M4"
		)
		(pin "M5"
		)
		(pin "R25"
		)
		(pin "H3"
		)
		(pin "H4"
		)
		(pin "AD13"
		)
		(pin "AD17"
		)
		(pin "N26"
		)
		(pin "R13"
		)
		(pin "N6"
		)
		(pin "N7"
		)
		(pin "U4"
		)
		(pin "R5"
		)
		(pin "K3"
		)
		(pin "K4"
		)
		(pin "AF3"
		)
		(pin "J5"
		)
		(pin "P2"
		)
		(pin "N22"
		)
		(pin "T16"
		)
		(pin "T17"
		)
		(pin "C3"
		)
		(pin "AF4"
		)
		(pin "T13"
		)
		(pin "AA12"
		)
		(pin "AB26"
		)
		(pin "AF21"
		)
		(pin "N25"
		)
		(pin "N3"
		)
		(pin "N21"
		)
		(pin "J12"
		)
		(pin "A8"
		)
		(pin "W12"
		)
		(pin "H14"
		)
		(pin "U21"
		)
		(pin "W9"
		)
		(pin "T14"
		)
		(pin "AE23"
		)
		(pin "K19"
		)
		(pin "K24"
		)
		(pin "Y25"
		)
		(pin "G12"
		)
		(pin "N2"
		)
		(pin "N20"
		)
		(pin "T25"
		)
		(pin "AC8"
		)
		(pin "E16"
		)
		(pin "AC19"
		)
		(pin "C14"
		)
		(pin "F4"
		)
		(pin "F5"
		)
		(pin "U19"
		)
		(pin "AE12"
		)
		(pin "P14"
		)
		(pin "AF8"
		)
		(pin "AF9"
		)
		(pin "V26"
		)
		(pin "W19"
		)
		(pin "L4"
		)
		(pin "G24"
		)
		(pin "R15"
		)
		(pin "R16"
		)
		(pin "U5"
		)
		(pin "AC16"
		)
		(pin "AF25"
		)
		(pin "T7"
		)
		(pin "F24"
		)
		(pin "D16"
		)
		(pin "AA19"
		)
		(pin "D5"
		)
		(pin "L22"
		)
		(pin "B17"
		)
		(pin "H15"
		)
		(pin "AE21"
		)
		(pin "AE7"
		)
		(pin "K5"
		)
		(pin "K6"
		)
		(pin "T1"
		)
		(pin "AE22"
		)
		(pin "E22"
		)
		(pin "AF10"
		)
		(pin "AB6"
		)
		(pin "AD26"
		)
		(pin "AC13"
		)
		(pin "E18"
		)
		(pin "M15"
		)
		(pin "M16"
		)
		(pin "G15"
		)
		(pin "N8"
		)
		(pin "N9"
		)
		(pin "W26"
		)
		(pin "F20"
		)
		(pin "AD23"
		)
		(pin "AA8"
		)
		(pin "D20"
		)
		(pin "AF11"
		)
		(pin "E8"
		)
		(pin "F11"
		)
		(pin "AC5"
		)
		(pin "AA22"
		)
		(pin "E20"
		)
		(pin "W14"
		)
		(pin "M19"
		)
		(pin "H24"
		)
		(pin "K7"
		)
		(pin "K8"
		)
		(pin "C4"
		)
		(pin "H25"
		)
		(pin "W21"
		)
		(pin "P13"
		)
		(pin "L20"
		)
		(pin "AB21"
		)
		(pin "C2"
		)
		(pin "H22"
		)
		(pin "Y17"
		)
		(pin "AE11"
		)
		(pin "H2"
		)
		(pin "F23"
		)
		(pin "E11"
		)
		(pin "AB24"
		)
		(pin "AA4"
		)
		(pin "T6"
		)
		(pin "AD20"
		)
		(pin "A10"
		)
		(pin "C9"
		)
		(pin "W15"
		)
		(pin "E21"
		)
		(pin "AB22"
		)
		(pin "W16"
		)
		(pin "AC25"
		)
		(pin "T22"
		)
		(pin "K1"
		)
		(pin "AD14"
		)
		(pin "T2"
		)
		(pin "J19"
		)
		(pin "D9"
		)
		(pin "AE17"
		)
		(pin "AB1"
		)
		(pin "T24"
		)
		(pin "F9"
		)
		(pin "M8"
		)
		(pin "M9"
		)
		(pin "Y23"
		)
		(pin "AC7"
		)
		(pin "M13"
		)
		(pin "M14"
		)
		(pin "G25"
		)
		(pin "A9"
		)
		(pin "AB19"
		)
		(pin "A7"
		)
		(pin "N15"
		)
		(pin "N16"
		)
		(pin "Y13"
		)
		(pin "AF5"
		)
		(pin "R14"
		)
		(pin "AE20"
		)
		(pin "AB11"
		)
		(pin "W25"
		)
		(pin "T19"
		)
		(pin "H21"
		)
		(pin "K2"
		)
		(pin "T23"
		)
		(pin "AC6"
		)
		(pin "B15"
		)
		(pin "E9"
		)
		(pin "AC3"
		)
		(pin "F10"
		)
		(pin "A3"
		)
		(pin "F15"
		)
		(pin "U20"
		)
		(pin "G10"
		)
		(pin "N23"
		)
		(pin "AB15"
		)
		(pin "AA21"
		)
		(pin "P10"
		)
		(pin "P11"
		)
		(pin "J11"
		)
		(pin "Y10"
		)
		(pin "F19"
		)
		(pin "A22"
		)
		(pin "AE16"
		)
		(pin "F22"
		)
		(pin "G11"
		)
		(pin "K25"
		)
		(pin "B10"
		)
		(pin "AA20"
		)
		(pin "N24"
		)
		(pin "AA25"
		)
		(pin "E12"
		)
		(pin "D11"
		)
		(pin "E14"
		)
		(pin "AC1"
		)
		(pin "J4"
		)
		(pin "H11"
		)
		(pin "H9"
		)
		(pin "M22"
		)
		(pin "H10"
		)
		(pin "E13"
		)
		(pin "AD21"
		)
		(pin "D10"
		)
		(pin "B11"
		)
		(pin "G26"
		)
		(pin "L25"
		)
		(pin "AB9"
		)
		(pin "A2"
		)
		(pin "M21"
		)
		(pin "C11"
		)
		(pin "R21"
		)
		(pin "D14"
		)
		(pin "F12"
		)
		(pin "B9"
		)
		(pin "J9"
		)
		(pin "L19"
		)
		(pin "B16"
		)
		(pin "K22"
		)
		(pin "K26"
		)
		(pin "N11"
		)
		(pin "N12"
		)
		(pin "A16"
		)
		(pin "AB12"
		)
		(pin "L7"
		)
		(pin "L8"
		)
		(pin "AC11"
		)
		(pin "J18"
		)
		(pin "K16"
		)
		(pin "K17"
		)
		(pin "M24"
		)
		(pin "M17"
		)
		(pin "M18"
		)
		(pin "J14"
		)
		(pin "R8"
		)
		(pin "R9"
		)
		(pin "A26"
		)
		(pin "H23"
		)
		(pin "AF16"
		)
		(pin "F26"
		)
		(pin "F3"
		)
		(pin "AC18"
		)
		(pin "W10"
		)
		(pin "G9"
		)
		(pin "K14"
		)
		(pin "K15"
		)
		(pin "N17"
		)
		(pin "N18"
		)
		(pin "AC9"
		)
		(pin "J13"
		)
		(pin "AE24"
		)
		(pin "AA23"
		)
		(pin "E2"
		)
		(pin "E3"
		)
		(pin "AE2"
		)
		(pin "AF26"
		)
		(pin "A21"
		)
		(pin "L9"
		)
		(pin "M10"
		)
		(pin "F16"
		)
		(pin "F21"
		)
		(pin "R26"
		)
		(pin "T12"
		)
		(pin "T15"
		)
		(pin "AB8"
		)
		(pin "A18"
		)
		(pin "A4"
		)
		(pin "AD11"
		)
		(instances
			(project "data-center-rdimm-ddr5-tester"
				(path ""
					(reference "U34")
					(unit 6)
				)
			)
		)
	)
	(symbol
		(lib_id "antmicropower:GND")
		(at 124.46 250.19 0)
		(unit 1)
		(exclude_from_sim no)
		(in_bom yes)
		(on_board yes)
		(dnp no)
		(fields_autoplaced yes)
		(property "Reference" "#PWR0433"
			(at 124.46 256.54 0)
			(effects
				(font
					(size 1.27 1.27)
				)
				(hide yes)
			)
		)
		(property "Value" "GND"
			(at 122.555 254.635 0)
			(effects
				(font
					(size 1.27 1.27)
					(thickness 0.15)
				)
				(justify left bottom)
			)
		)
		(property "Footprint" ""
			(at 133.35 257.81 0)
			(effects
				(font
					(size 1.27 1.27)
					(thickness 0.15)
				)
				(justify left bottom)
				(hide yes)
			)
		)
		(property "Datasheet" ""
			(at 133.35 262.89 0)
			(effects
				(font
					(size 1.27 1.27)
					(thickness 0.15)
				)
				(justify left bottom)
				(hide yes)
			)
		)
		(property "Description" ""
			(at 124.46 250.19 0)
			(effects
				(font
					(size 1.27 1.27)
				)
				(hide yes)
			)
		)
		(property "Author" "Antmicro"
			(at 133.35 255.27 0)
			(effects
				(font
					(size 1.27 1.27)
					(thickness 0.15)
				)
				(justify left bottom)
				(hide yes)
			)
		)
		(property "License" "Apache-2.0"
			(at 133.35 257.81 0)
			(effects
				(font
					(size 1.27 1.27)
					(thickness 0.15)
				)
				(justify left bottom)
				(hide yes)
			)
		)
		(pin "1"
		)
		(instances
			(project "data-center-rdimm-ddr5-tester"
				(path ""
					(reference "#PWR0433")
					(unit 1)
				)
			)
		)
	)
	(symbol
		(lib_id "antmicroTransistorsFETsMOSFETsSingle:BSS138PW")
		(at 78.74 245.11 0)
		(unit 1)
		(exclude_from_sim no)
		(in_bom yes)
		(on_board yes)
		(dnp no)
		(fields_autoplaced yes)
		(property "Reference" "Q8"
			(at 90.17 241.3 0)
			(effects
				(font
					(size 1.27 1.27)
					(thickness 0.15)
				)
				(justify left)
			)
		)
		(property "Value" "BSS138PW"
			(at 101.6 254 0)
			(effects
				(font
					(size 1.27 1.27)
					(thickness 0.15)
				)
				(justify left bottom)
				(hide yes)
			)
		)
		(property "Footprint" "antmicro-footprints:SC70-3"
			(at 101.6 256.54 0)
			(effects
				(font
					(size 1.27 1.27)
					(thickness 0.15)
				)
				(justify left bottom)
				(hide yes)
			)
		)
		(property "Datasheet" "https://assets.nexperia.com/documents/data-sheet/BSS138PW.pdf"
			(at 101.6 259.08 0)
			(effects
				(font
					(size 1.27 1.27)
					(thickness 0.15)
				)
				(justify left bottom)
				(hide yes)
			)
		)
		(property "Description" ""
			(at 78.74 245.11 0)
			(effects
				(font
					(size 1.27 1.27)
				)
				(hide yes)
			)
		)
		(property "MPN" "BSS138PW"
			(at 90.17 243.84 0)
			(effects
				(font
					(size 1.27 1.27)
					(thickness 0.15)
				)
				(justify left)
			)
		)
		(property "Manufacturer" "Nexperia"
			(at 101.6 264.16 0)
			(effects
				(font
					(size 1.27 1.27)
					(thickness 0.15)
				)
				(justify left bottom)
				(hide yes)
			)
		)
		(property "Author" "Antmicro"
			(at 101.6 266.7 0)
			(effects
				(font
					(size 1.27 1.27)
					(thickness 0.15)
				)
				(justify left bottom)
				(hide yes)
			)
		)
		(property "License" "Apache-2.0"
			(at 101.6 269.24 0)
			(effects
				(font
					(size 1.27 1.27)
					(thickness 0.15)
				)
				(justify left bottom)
				(hide yes)
			)
		)
		(pin "2"
		)
		(pin "3"
		)
		(pin "1"
		)
		(instances
			(project "data-center-rdimm-ddr5-tester"
				(path ""
					(reference "Q8")
					(unit 1)
				)
			)
		)
	)
	(symbol
		(lib_id "antmicropower:+3V3")
		(at 204.47 64.77 0)
		(unit 1)
		(exclude_from_sim no)
		(in_bom yes)
		(on_board yes)
		(dnp no)
		(fields_autoplaced yes)
		(property "Reference" "#PWR0154"
			(at 204.47 68.58 0)
			(effects
				(font
					(size 1.27 1.27)
				)
				(hide yes)
			)
		)
		(property "Value" "+3V3"
			(at 201.295 62.23 0)
			(effects
				(font
					(size 1.27 1.27)
					(thickness 0.15)
				)
				(justify left bottom)
			)
		)
		(property "Footprint" ""
			(at 219.71 72.39 0)
			(effects
				(font
					(size 1.27 1.27)
					(thickness 0.15)
				)
				(justify left bottom)
				(hide yes)
			)
		)
		(property "Datasheet" ""
			(at 219.71 74.93 0)
			(effects
				(font
					(size 1.27 1.27)
					(thickness 0.15)
				)
				(justify left bottom)
				(hide yes)
			)
		)
		(property "Description" ""
			(at 204.47 64.77 0)
			(effects
				(font
					(size 1.27 1.27)
				)
				(hide yes)
			)
		)
		(property "Author" "Antmicro"
			(at 219.71 67.31 0)
			(effects
				(font
					(size 1.27 1.27)
					(thickness 0.15)
				)
				(justify left bottom)
				(hide yes)
			)
		)
		(property "License" "Apache-2.0"
			(at 219.71 69.85 0)
			(effects
				(font
					(size 1.27 1.27)
					(thickness 0.15)
				)
				(justify left bottom)
				(hide yes)
			)
		)
		(pin "1"
		)
		(instances
			(project "data-center-rdimm-ddr5-tester"
				(path ""
					(reference "#PWR0154")
					(unit 1)
				)
			)
		)
	)
	(symbol
		(lib_id "antmicropower:+3V3")
		(at 193.04 219.71 0)
		(unit 1)
		(exclude_from_sim no)
		(in_bom yes)
		(on_board yes)
		(dnp no)
		(property "Reference" "#PWR0428"
			(at 193.04 223.52 0)
			(effects
				(font
					(size 1.27 1.27)
				)
				(hide yes)
			)
		)
		(property "Value" "+3V3"
			(at 189.865 217.17 0)
			(effects
				(font
					(size 1.27 1.27)
					(thickness 0.15)
				)
				(justify left bottom)
			)
		)
		(property "Footprint" ""
			(at 208.28 227.33 0)
			(effects
				(font
					(size 1.27 1.27)
					(thickness 0.15)
				)
				(justify left bottom)
				(hide yes)
			)
		)
		(property "Datasheet" ""
			(at 208.28 229.87 0)
			(effects
				(font
					(size 1.27 1.27)
					(thickness 0.15)
				)
				(justify left bottom)
				(hide yes)
			)
		)
		(property "Description" ""
			(at 193.04 219.71 0)
			(effects
				(font
					(size 1.27 1.27)
				)
				(hide yes)
			)
		)
		(property "Author" "Antmicro"
			(at 208.28 222.25 0)
			(effects
				(font
					(size 1.27 1.27)
					(thickness 0.15)
				)
				(justify left bottom)
				(hide yes)
			)
		)
		(property "License" "Apache-2.0"
			(at 208.28 224.79 0)
			(effects
				(font
					(size 1.27 1.27)
					(thickness 0.15)
				)
				(justify left bottom)
				(hide yes)
			)
		)
		(pin "1"
		)
		(instances
			(project "data-center-rdimm-ddr5-tester"
				(path ""
					(reference "#PWR0428")
					(unit 1)
				)
			)
		)
	)
	(symbol
		(lib_id "antmicropower:+3V3")
		(at 124.46 219.71 0)
		(unit 1)
		(exclude_from_sim no)
		(in_bom yes)
		(on_board yes)
		(dnp no)
		(fields_autoplaced yes)
		(property "Reference" "#PWR0432"
			(at 124.46 223.52 0)
			(effects
				(font
					(size 1.27 1.27)
				)
				(hide yes)
			)
		)
		(property "Value" "+3V3"
			(at 121.285 217.17 0)
			(effects
				(font
					(size 1.27 1.27)
					(thickness 0.15)
				)
				(justify left bottom)
			)
		)
		(property "Footprint" ""
			(at 139.7 227.33 0)
			(effects
				(font
					(size 1.27 1.27)
					(thickness 0.15)
				)
				(justify left bottom)
				(hide yes)
			)
		)
		(property "Datasheet" ""
			(at 139.7 229.87 0)
			(effects
				(font
					(size 1.27 1.27)
					(thickness 0.15)
				)
				(justify left bottom)
				(hide yes)
			)
		)
		(property "Description" ""
			(at 124.46 219.71 0)
			(effects
				(font
					(size 1.27 1.27)
				)
				(hide yes)
			)
		)
		(property "Author" "Antmicro"
			(at 139.7 222.25 0)
			(effects
				(font
					(size 1.27 1.27)
					(thickness 0.15)
				)
				(justify left bottom)
				(hide yes)
			)
		)
		(property "License" "Apache-2.0"
			(at 139.7 224.79 0)
			(effects
				(font
					(size 1.27 1.27)
					(thickness 0.15)
				)
				(justify left bottom)
				(hide yes)
			)
		)
		(pin "1"
		)
		(instances
			(project "data-center-rdimm-ddr5-tester"
				(path ""
					(reference "#PWR0432")
					(unit 1)
				)
			)
		)
	)
	(symbol
		(lib_id "antmicropower:GND")
		(at 86.36 250.19 0)
		(unit 1)
		(exclude_from_sim no)
		(in_bom yes)
		(on_board yes)
		(dnp no)
		(fields_autoplaced yes)
		(property "Reference" "#PWR0435"
			(at 86.36 256.54 0)
			(effects
				(font
					(size 1.27 1.27)
				)
				(hide yes)
			)
		)
		(property "Value" "GND"
			(at 84.455 254.635 0)
			(effects
				(font
					(size 1.27 1.27)
					(thickness 0.15)
				)
				(justify left bottom)
			)
		)
		(property "Footprint" ""
			(at 95.25 257.81 0)
			(effects
				(font
					(size 1.27 1.27)
					(thickness 0.15)
				)
				(justify left bottom)
				(hide yes)
			)
		)
		(property "Datasheet" ""
			(at 95.25 262.89 0)
			(effects
				(font
					(size 1.27 1.27)
					(thickness 0.15)
				)
				(justify left bottom)
				(hide yes)
			)
		)
		(property "Description" ""
			(at 86.36 250.19 0)
			(effects
				(font
					(size 1.27 1.27)
				)
				(hide yes)
			)
		)
		(property "Author" "Antmicro"
			(at 95.25 255.27 0)
			(effects
				(font
					(size 1.27 1.27)
					(thickness 0.15)
				)
				(justify left bottom)
				(hide yes)
			)
		)
		(property "License" "Apache-2.0"
			(at 95.25 257.81 0)
			(effects
				(font
					(size 1.27 1.27)
					(thickness 0.15)
				)
				(justify left bottom)
				(hide yes)
			)
		)
		(pin "1"
		)
		(instances
			(project "data-center-rdimm-ddr5-tester"
				(path ""
					(reference "#PWR0435")
					(unit 1)
				)
			)
		)
	)
	(symbol
		(lib_id "antmicroTransistorsFETsMOSFETsSingle:BSS138PW")
		(at 219.71 245.11 0)
		(unit 1)
		(exclude_from_sim no)
		(in_bom yes)
		(on_board yes)
		(dnp no)
		(fields_autoplaced yes)
		(property "Reference" "Q4"
			(at 231.14 241.3 0)
			(effects
				(font
					(size 1.27 1.27)
					(thickness 0.15)
				)
				(justify left)
			)
		)
		(property "Value" "BSS138PW"
			(at 242.57 254 0)
			(effects
				(font
					(size 1.27 1.27)
					(thickness 0.15)
				)
				(justify left bottom)
				(hide yes)
			)
		)
		(property "Footprint" "antmicro-footprints:SC70-3"
			(at 242.57 256.54 0)
			(effects
				(font
					(size 1.27 1.27)
					(thickness 0.15)
				)
				(justify left bottom)
				(hide yes)
			)
		)
		(property "Datasheet" "https://assets.nexperia.com/documents/data-sheet/BSS138PW.pdf"
			(at 242.57 259.08 0)
			(effects
				(font
					(size 1.27 1.27)
					(thickness 0.15)
				)
				(justify left bottom)
				(hide yes)
			)
		)
		(property "Description" ""
			(at 219.71 245.11 0)
			(effects
				(font
					(size 1.27 1.27)
				)
				(hide yes)
			)
		)
		(property "MPN" "BSS138PW"
			(at 231.14 243.84 0)
			(effects
				(font
					(size 1.27 1.27)
					(thickness 0.15)
				)
				(justify left)
			)
		)
		(property "Manufacturer" "Nexperia"
			(at 242.57 264.16 0)
			(effects
				(font
					(size 1.27 1.27)
					(thickness 0.15)
				)
				(justify left bottom)
				(hide yes)
			)
		)
		(property "Author" "Antmicro"
			(at 242.57 266.7 0)
			(effects
				(font
					(size 1.27 1.27)
					(thickness 0.15)
				)
				(justify left bottom)
				(hide yes)
			)
		)
		(property "License" "Apache-2.0"
			(at 242.57 269.24 0)
			(effects
				(font
					(size 1.27 1.27)
					(thickness 0.15)
				)
				(justify left bottom)
				(hide yes)
			)
		)
		(pin "2"
		)
		(pin "3"
		)
		(pin "1"
		)
		(instances
			(project "data-center-rdimm-ddr5-tester"
				(path ""
					(reference "Q4")
					(unit 1)
				)
			)
		)
	)
	(symbol
		(lib_id "antmicroTransistorsFETsMOSFETsSingle:BSS138PW")
		(at 151.13 245.11 0)
		(unit 1)
		(exclude_from_sim no)
		(in_bom yes)
		(on_board yes)
		(dnp no)
		(fields_autoplaced yes)
		(property "Reference" "Q6"
			(at 162.56 241.3 0)
			(effects
				(font
					(size 1.27 1.27)
					(thickness 0.15)
				)
				(justify left)
			)
		)
		(property "Value" "BSS138PW"
			(at 173.99 254 0)
			(effects
				(font
					(size 1.27 1.27)
					(thickness 0.15)
				)
				(justify left bottom)
				(hide yes)
			)
		)
		(property "Footprint" "antmicro-footprints:SC70-3"
			(at 173.99 256.54 0)
			(effects
				(font
					(size 1.27 1.27)
					(thickness 0.15)
				)
				(justify left bottom)
				(hide yes)
			)
		)
		(property "Datasheet" "https://assets.nexperia.com/documents/data-sheet/BSS138PW.pdf"
			(at 173.99 259.08 0)
			(effects
				(font
					(size 1.27 1.27)
					(thickness 0.15)
				)
				(justify left bottom)
				(hide yes)
			)
		)
		(property "Description" ""
			(at 151.13 245.11 0)
			(effects
				(font
					(size 1.27 1.27)
				)
				(hide yes)
			)
		)
		(property "MPN" "BSS138PW"
			(at 162.56 243.84 0)
			(effects
				(font
					(size 1.27 1.27)
					(thickness 0.15)
				)
				(justify left)
			)
		)
		(property "Manufacturer" "Nexperia"
			(at 173.99 264.16 0)
			(effects
				(font
					(size 1.27 1.27)
					(thickness 0.15)
				)
				(justify left bottom)
				(hide yes)
			)
		)
		(property "Author" "Antmicro"
			(at 173.99 266.7 0)
			(effects
				(font
					(size 1.27 1.27)
					(thickness 0.15)
				)
				(justify left bottom)
				(hide yes)
			)
		)
		(property "License" "Apache-2.0"
			(at 173.99 269.24 0)
			(effects
				(font
					(size 1.27 1.27)
					(thickness 0.15)
				)
				(justify left bottom)
				(hide yes)
			)
		)
		(pin "2"
		)
		(pin "3"
		)
		(pin "1"
		)
		(instances
			(project "data-center-rdimm-ddr5-tester"
				(path ""
					(reference "Q6")
					(unit 1)
				)
			)
		)
	)
	(symbol
		(lib_id "antmicroResistors0402:R_330R_0402")
		(at 86.36 229.87 270)
		(unit 1)
		(exclude_from_sim no)
		(in_bom yes)
		(on_board yes)
		(dnp no)
		(fields_autoplaced yes)
		(property "Reference" "R46"
			(at 88.011 231.5794 90)
			(effects
				(font
					(size 1.27 1.27)
				)
				(justify left)
			)
		)
		(property "Value" "R_330R_0402"
			(at 73.66 250.19 0)
			(effects
				(font
					(size 1.27 1.27)
					(thickness 0.15)
				)
				(justify left bottom)
				(hide yes)
			)
		)
		(property "Footprint" "antmicro-footprints:R_0402_1005Metric"
			(at 71.12 250.19 0)
			(effects
				(font
					(size 1.27 1.27)
					(thickness 0.15)
				)
				(justify left bottom)
				(hide yes)
			)
		)
		(property "Datasheet" "https://www.bourns.com/docs/product-datasheets/cr.pdf"
			(at 68.58 250.19 0)
			(effects
				(font
					(size 1.27 1.27)
					(thickness 0.15)
				)
				(justify left bottom)
				(hide yes)
			)
		)
		(property "Description" ""
			(at 86.36 229.87 0)
			(effects
				(font
					(size 1.27 1.27)
				)
				(hide yes)
			)
		)
		(property "Manufacturer" "Bourns"
			(at 63.5 250.19 0)
			(effects
				(font
					(size 1.27 1.27)
					(thickness 0.15)
				)
				(justify left bottom)
				(hide yes)
			)
		)
		(property "MPN" "CR0402-FX-3300GLF"
			(at 66.04 250.19 0)
			(effects
				(font
					(size 1.27 1.27)
					(thickness 0.15)
				)
				(justify left bottom)
				(hide yes)
			)
		)
		(property "Val" "330R"
			(at 88.011 234.1097 90)
			(effects
				(font
					(size 1.27 1.27)
					(thickness 0.15)
				)
				(justify left)
			)
		)
		(property "License" "Apache-2.0"
			(at 60.96 250.19 0)
			(effects
				(font
					(size 1.27 1.27)
					(thickness 0.15)
				)
				(justify left bottom)
				(hide yes)
			)
		)
		(property "Author" "Antmicro"
			(at 58.42 250.19 0)
			(effects
				(font
					(size 1.27 1.27)
					(thickness 0.15)
				)
				(justify left bottom)
				(hide yes)
			)
		)
		(property "Tolerance" "1%"
			(at 76.2 250.19 0)
			(effects
				(font
					(size 1.27 1.27)
				)
				(justify left bottom)
				(hide yes)
			)
		)
		(pin "1"
		)
		(pin "2"
		)
		(instances
			(project "data-center-rdimm-ddr5-tester"
				(path ""
					(reference "R46")
					(unit 1)
				)
			)
		)
	)
)
